FILE_TYPE = MACRO_DRAWING;
SET COLOR_WIRE YELLOW;
SET COLOR_PROP MONO;
SET COLOR_DOT WHITE;
SET COLOR_ARC YELLOW;
SET COLOR_BODY GREEN;
SET COLOR_NOTE MONO;
SET PROP_DISPLAY VALUE;
SET PAGE_NUMBER P202;
FORCEADD OFFPAGE..2
(-1400 4750);
FORCEPROP 2 LAST $XR0 201 
J 0
(-1211 4750);
DISPLAY 0.638298 (-1211 4750);
PAINT MONO (-1211 4750);
FORCEPROP 2 LAST BOM_COST PROC_VRD_VCCIN_CPU0
J 0
(-1200 4800);
DISPLAY 1.446809 (-1200 4800);
PAINT MONO (-1200 4800);
DISPLAY INVISIBLE (-1200 4800);
FORCEPROP 1 LAST OFFPAGE TRUE
J 0
(-1075 4625);
DISPLAY 1.723404 (-1075 4625);
PAINT GREEN (-1075 4625);
DISPLAY INVISIBLE (-1075 4625);
FORCEPROP 2 LAST PATH I1
J 0
(-1195 4800);
DISPLAY 1.021277 (-1195 4800);
PAINT ORANGE (-1195 4800);
DISPLAY INVISIBLE (-1195 4800);
FORCEPROP 2 LAST CDS_LIB mstr_standard
J 2
(-1400 4750);
DISPLAY 1.936170 (-1400 4750);
PAINT ORANGE (-1400 4750);
DISPLAY INVISIBLE (-1400 4750);
FORCEPROP 1 LAST COMMENT_BODY TRUE
J 0
(-1445 4655);
DISPLAY 1.723404 (-1445 4655);
PAINT GREEN (-1445 4655);
DISPLAY INVISIBLE (-1445 4655);
FORCEPROP 2 LAST ROOM PVCCIN_CPU0_PWR_VR
J 0
(-1800 4825);
DISPLAY 1.936170 (-1800 4825);
PAINT ORANGE (-1800 4825);
DISPLAY INVISIBLE (-1800 4825);
FORCEADD OFFPAGE..2
(-1725 2100);
FORCEPROP 2 LAST $XR0 201 
J 0
(-1536 2100);
DISPLAY 0.638298 (-1536 2100);
PAINT MONO (-1536 2100);
FORCEPROP 2 LAST BOM_COST PROC_VRD_VCCIN_CPU0
J 0
(-1525 2150);
DISPLAY 1.446809 (-1525 2150);
PAINT MONO (-1525 2150);
DISPLAY INVISIBLE (-1525 2150);
FORCEPROP 2 LAST PATH I10
J 0
(-1545 2175);
DISPLAY 1.021277 (-1545 2175);
PAINT ORANGE (-1545 2175);
DISPLAY INVISIBLE (-1545 2175);
FORCEPROP 2 LAST CDS_LIB mstr_standard
J 0
(-1725 2100);
PAINT ORANGE (-1725 2100);
DISPLAY INVISIBLE (-1725 2100);
FORCEPROP 1 LAST COMMENT_BODY TRUE
J 0
(-1770 2005);
DISPLAY 1.723404 (-1770 2005);
PAINT GREEN (-1770 2005);
DISPLAY INVISIBLE (-1770 2005);
FORCEPROP 1 LAST OFFPAGE TRUE
J 0
(-1400 1975);
DISPLAY 1.723404 (-1400 1975);
PAINT GREEN (-1400 1975);
DISPLAY INVISIBLE (-1400 1975);
FORCEPROP 2 LAST ROOM PVCCIN_CPU0_PWR_VR
J 0
(-2125 2175);
DISPLAY 1.936170 (-2125 2175);
PAINT ORANGE (-2125 2175);
DISPLAY INVISIBLE (-2125 2175);
FORCEADD OFFPAGE..2
(-1675 1725);
FORCEPROP 2 LAST $XR0 201 
J 0
(-1486 1725);
DISPLAY 0.638298 (-1486 1725);
PAINT MONO (-1486 1725);
FORCEPROP 2 LAST BOM_COST PROC_VRD_VCCIN_CPU0
J 0
(-1475 1775);
DISPLAY 1.446809 (-1475 1775);
PAINT MONO (-1475 1775);
DISPLAY INVISIBLE (-1475 1775);
FORCEPROP 1 LAST OFFPAGE TRUE
J 0
(-1350 1600);
DISPLAY 1.723404 (-1350 1600);
PAINT GREEN (-1350 1600);
DISPLAY INVISIBLE (-1350 1600);
FORCEPROP 2 LAST PATH I11
J 0
(-1495 1800);
DISPLAY 1.021277 (-1495 1800);
PAINT ORANGE (-1495 1800);
DISPLAY INVISIBLE (-1495 1800);
FORCEPROP 2 LAST CDS_LIB mstr_standard
J 0
(-1675 1725);
PAINT ORANGE (-1675 1725);
DISPLAY INVISIBLE (-1675 1725);
FORCEPROP 1 LAST COMMENT_BODY TRUE
J 0
(-1720 1630);
DISPLAY 1.723404 (-1720 1630);
PAINT GREEN (-1720 1630);
DISPLAY INVISIBLE (-1720 1630);
FORCEPROP 2 LAST ROOM PVCCIN_CPU0_PWR_VR
J 0
(-2075 1800);
DISPLAY 1.936170 (-2075 1800);
PAINT ORANGE (-2075 1800);
DISPLAY INVISIBLE (-2075 1800);
FORCEADD OFFPAGE..2
(-1675 1375);
FORCEPROP 2 LAST $XR2 204 
J 0
(-1246 1375);
DISPLAY 0.638298 (-1246 1375);
PAINT MONO (-1246 1375);
FORCEPROP 2 LAST $XR3 201 
J 0
(-1126 1375);
DISPLAY 0.638298 (-1126 1375);
PAINT MONO (-1126 1375);
FORCEPROP 2 LAST $XR1 203 
J 0
(-1366 1375);
DISPLAY 0.638298 (-1366 1375);
PAINT MONO (-1366 1375);
FORCEPROP 2 LAST $XR0 202 
J 0
(-1486 1375);
DISPLAY 0.638298 (-1486 1375);
PAINT MONO (-1486 1375);
FORCEPROP 2 LAST BOM_COST PROC_VRD_VCCIN_CPU0
J 0
(-1475 1425);
DISPLAY 1.446809 (-1475 1425);
PAINT MONO (-1475 1425);
DISPLAY INVISIBLE (-1475 1425);
FORCEPROP 1 LAST OFFPAGE TRUE
J 0
(-1350 1250);
DISPLAY 1.723404 (-1350 1250);
PAINT GREEN (-1350 1250);
DISPLAY INVISIBLE (-1350 1250);
FORCEPROP 2 LAST PATH I12
J 0
(-1495 1450);
DISPLAY 1.021277 (-1495 1450);
PAINT ORANGE (-1495 1450);
DISPLAY INVISIBLE (-1495 1450);
FORCEPROP 2 LAST CDS_LIB mstr_standard
J 0
(-1675 1375);
PAINT ORANGE (-1675 1375);
DISPLAY INVISIBLE (-1675 1375);
FORCEPROP 1 LAST COMMENT_BODY TRUE
J 0
(-1720 1280);
DISPLAY 1.723404 (-1720 1280);
PAINT GREEN (-1720 1280);
DISPLAY INVISIBLE (-1720 1280);
FORCEPROP 2 LAST ROOM PVCCIN_CPU0_PWR_VR
J 0
(-2075 1450);
DISPLAY 1.936170 (-2075 1450);
PAINT ORANGE (-2075 1450);
DISPLAY INVISIBLE (-2075 1450);
FORCEADD GND..1
(-2800 3125);
FORCEPROP 3 LASTPIN (-2800 3175) SIG_NAME GND\g
J 0
(-2790 3185);
DISPLAY 0.659574 (-2790 3185);
PAINT MONO (-2790 3185);
DISPLAY INVISIBLE (-2790 3185);
FORCEPROP 1 LAST HDL_POWER GND
J 0
(-2800 3275);
DISPLAY 1.723404 (-2800 3275);
PAINT GREEN (-2800 3275);
DISPLAY INVISIBLE (-2800 3275);
FORCEPROP 1 LAST SIZE 1B
J 0
(-2725 3075);
DISPLAY 1.723404 (-2725 3075);
PAINT GREEN (-2725 3075);
DISPLAY INVISIBLE (-2725 3075);
FORCEPROP 1 LAST VOLTAGE 0
J 0
(-2800 3125);
PAINT SKYBLUE (-2800 3125);
DISPLAY INVISIBLE (-2800 3125);
FORCEPROP 1 LAST BODY_TYPE PLUMBING
J 0
(-2845 3082);
DISPLAY 0.340426 (-2845 3082);
PAINT GREEN (-2845 3082);
DISPLAY INVISIBLE (-2845 3082);
FORCEPROP 2 LAST BOM_COST PROC_VRD_VCCIN_CPU0
J 0
(-3175 3200);
DISPLAY 1.446809 (-3175 3200);
PAINT MONO (-3175 3200);
DISPLAY INVISIBLE (-3175 3200);
FORCEPROP 2 LAST ROOM PVCCIN_CPU0_PWR_VR
J 0
(-3350 3200);
DISPLAY 1.936170 (-3350 3200);
PAINT ORANGE (-3350 3200);
DISPLAY INVISIBLE (-3350 3200);
FORCEPROP 1 LAST PATH I13
J 0
(-2725 3125);
DISPLAY 0.872340 (-2725 3125);
PAINT AQUA (-2725 3125);
DISPLAY INVISIBLE (-2725 3125);
FORCEPROP 2 LAST CDS_LIB mstr_symbols
J 0
(-2800 3125);
DISPLAY 1.936170 (-2800 3125);
PAINT ORANGE (-2800 3125);
DISPLAY INVISIBLE (-2800 3125);
FORCEADD CAP..1
(-5025 4125);
FORCEPROP 1 LAST VOLTAGE 16V
J 0
(-4975 4125);
DISPLAY 0.617021 (-4975 4125);
PAINT SKYBLUE (-4975 4125);
FORCEPROP 1 LAST VALUE 0.22UF
J 0
(-4975 4175);
DISPLAY 0.617021 (-4975 4175);
PAINT SKYBLUE (-4975 4175);
FORCEPROP 1 LAST PACK_TYPE 0402
J 0
(-4975 3925);
DISPLAY 0.617021 (-4975 3925);
PAINT SKYBLUE (-4975 3925);
FORCEPROP 1 LAST LOCATION C4E5
J 0
(-4975 4225);
DISPLAY 0.617021 (-4975 4225);
PAINT AQUA (-4975 4225);
FORCEPROP 1 LASTPIN (-5025 4225) $PN 1
J 0
(-5015 4205);
DISPLAY 0.617021 (-5015 4205);
PAINT ORANGE (-5015 4205);
FORCEPROP 1 LAST TOLERANCE 10%
J 0
(-4975 4075);
DISPLAY 0.617021 (-4975 4075);
PAINT SKYBLUE (-4975 4075);
FORCEPROP 1 LASTPIN (-5025 4025) $PN 2
J 0
(-5015 4005);
DISPLAY 0.617021 (-5015 4005);
PAINT ORANGE (-5015 4005);
FORCEPROP 1 LAST MATERIAL X7R
J 0
(-4975 4025);
DISPLAY 0.617021 (-4975 4025);
PAINT SKYBLUE (-4975 4025);
FORCEPROP 1 LAST PART_NUMBER A36096-155
J 0
(-4975 3975);
DISPLAY 0.617021 (-4975 3975);
PAINT BLUE (-4975 3975);
FORCEPROP 2 LAST ROOM PVCCIN_CPU0_PWR_VR
J 0
(-4975 4275);
DISPLAY 1.361702 (-4975 4275);
PAINT ORANGE (-4975 4275);
DISPLAY INVISIBLE (-4975 4275);
FORCEPROP 1 LAST PATH I18
J 0
(-4975 4275);
DISPLAY 0.978723 (-4975 4275);
PAINT WHITE (-4975 4275);
DISPLAY INVISIBLE (-4975 4275);
FORCEPROP 2 LAST CDS_LOCATION C4E5
J 0
(-4975 4225);
DISPLAY 0.617021 (-4975 4225);
PAINT AQUA (-4975 4225);
DISPLAY INVISIBLE (-4975 4225);
FORCEPROP 2 LAST SEC 1
J 0
(-4975 4325);
DISPLAY 0.680851 (-4975 4325);
PAINT MONO (-4975 4325);
DISPLAY INVISIBLE (-4975 4325);
FORCEPROP 2 LAST SEC_TYPE 0402
J 0
(-4975 4325);
DISPLAY 1.021277 (-4975 4325);
PAINT ORANGE (-4975 4325);
DISPLAY INVISIBLE (-4975 4325);
FORCEPROP 2 LAST CDS_LIB mstr_discrete
J 0
(-5025 4125);
PAINT ORANGE (-5025 4125);
DISPLAY INVISIBLE (-5025 4125);
FORCEADD CAP_A..1
R 2
(-5125 4125);
FORCEPROP 1 LAST VALUE 1.0UF
J 2
(-5175 4175);
DISPLAY 0.617021 (-5175 4175);
PAINT SKYBLUE (-5175 4175);
FORCEPROP 1 LAST MATERIAL X6S
J 2
(-5175 4025);
DISPLAY 0.617021 (-5175 4025);
PAINT SKYBLUE (-5175 4025);
FORCEPROP 1 LAST PACK_TYPE 0402V
J 2
(-5175 3925);
DISPLAY 0.617021 (-5175 3925);
PAINT SKYBLUE (-5175 3925);
FORCEPROP 1 LAST LOCATION C4E6
J 2
(-5175 4225);
DISPLAY 0.617021 (-5175 4225);
PAINT AQUA (-5175 4225);
FORCEPROP 1 LAST VOLTAGE 6.3V
J 2
(-5175 4125);
DISPLAY 0.617021 (-5175 4125);
PAINT SKYBLUE (-5175 4125);
FORCEPROP 1 LASTPIN (-5125 4225) $PN 1
J 2
(-5135 4205);
DISPLAY 0.617021 (-5135 4205);
PAINT ORANGE (-5135 4205);
FORCEPROP 1 LAST TOLERANCE 10%
J 2
(-5175 4075);
DISPLAY 0.617021 (-5175 4075);
PAINT SKYBLUE (-5175 4075);
FORCEPROP 1 LASTPIN (-5125 4025) $PN 2
J 2
(-5135 4005);
DISPLAY 0.617021 (-5135 4005);
PAINT ORANGE (-5135 4005);
FORCEPROP 1 LAST PART_NUMBER D97712-004
J 2
(-5175 3975);
DISPLAY 0.617021 (-5175 3975);
PAINT BLUE (-5175 3975);
FORCEPROP 2 LAST ROOM PVCCIN_CPU0_PWR_VR
J 0
(-5175 4275);
DISPLAY 1.361702 (-5175 4275);
PAINT ORANGE (-5175 4275);
DISPLAY INVISIBLE (-5175 4275);
FORCEPROP 1 LAST PATH I19
J 2
(-5175 4275);
DISPLAY 0.978723 (-5175 4275);
PAINT WHITE (-5175 4275);
DISPLAY INVISIBLE (-5175 4275);
FORCEPROP 2 LAST SEC 1
J 0
(-5175 4325);
DISPLAY 0.680851 (-5175 4325);
PAINT MONO (-5175 4325);
DISPLAY INVISIBLE (-5175 4325);
FORCEPROP 2 LAST SEC_TYPE 0402V
J 0
(-5175 4325);
DISPLAY 1.021277 (-5175 4325);
PAINT ORANGE (-5175 4325);
DISPLAY INVISIBLE (-5175 4325);
FORCEPROP 2 LAST CDS_SEC 1
J 0
(-5175 4275);
PAINT ORANGE (-5175 4275);
DISPLAY INVISIBLE (-5175 4275);
FORCEPROP 2 LAST CDS_LIB dev_discrete
J 0
(-5125 4125);
PAINT ORANGE (-5125 4125);
DISPLAY INVISIBLE (-5125 4125);
FORCEPROP 2 LAST CDS_LOCATION C4E6
J 2
(-5175 4225);
DISPLAY 0.617021 (-5175 4225);
PAINT AQUA (-5175 4225);
DISPLAY INVISIBLE (-5175 4225);
FORCEADD OFFPAGE..2
(-1550 4350);
FORCEPROP 2 LAST $XR0 201 
J 0
(-1361 4350);
DISPLAY 0.638298 (-1361 4350);
PAINT MONO (-1361 4350);
FORCEPROP 2 LAST BOM_COST PROC_VRD_VCCIN_CPU0
J 0
(-1350 4400);
DISPLAY 1.446809 (-1350 4400);
PAINT MONO (-1350 4400);
DISPLAY INVISIBLE (-1350 4400);
FORCEPROP 1 LAST OFFPAGE TRUE
J 0
(-1225 4225);
DISPLAY 1.723404 (-1225 4225);
PAINT GREEN (-1225 4225);
DISPLAY INVISIBLE (-1225 4225);
FORCEPROP 2 LAST PATH I2
J 0
(-1345 4400);
DISPLAY 1.021277 (-1345 4400);
PAINT ORANGE (-1345 4400);
DISPLAY INVISIBLE (-1345 4400);
FORCEPROP 2 LAST ROOM PVCCIN_CPU0_PWR_VR
J 0
(-1950 4425);
DISPLAY 1.936170 (-1950 4425);
PAINT ORANGE (-1950 4425);
DISPLAY INVISIBLE (-1950 4425);
FORCEPROP 2 LAST CDS_LIB mstr_standard
J 0
(-1550 4350);
DISPLAY 1.936170 (-1550 4350);
PAINT ORANGE (-1550 4350);
DISPLAY INVISIBLE (-1550 4350);
FORCEPROP 1 LAST COMMENT_BODY TRUE
J 0
(-1595 4255);
DISPLAY 1.723404 (-1595 4255);
PAINT GREEN (-1595 4255);
DISPLAY INVISIBLE (-1595 4255);
FORCEADD CAP..1
R 2
(-5850 3450);
FORCEPROP 1 LAST PACK_TYPE 0402
J 2
(-5900 3250);
DISPLAY 0.617021 (-5900 3250);
PAINT SKYBLUE (-5900 3250);
FORCEPROP 1 LAST MATERIAL X7R
J 2
(-5900 3350);
DISPLAY 0.617021 (-5900 3350);
PAINT SKYBLUE (-5900 3350);
FORCEPROP 1 LAST TOLERANCE 10%
J 2
(-5900 3400);
DISPLAY 0.617021 (-5900 3400);
PAINT SKYBLUE (-5900 3400);
FORCEPROP 1 LAST LOCATION C4E17
J 2
(-5900 3550);
DISPLAY 0.617021 (-5900 3550);
PAINT AQUA (-5900 3550);
FORCEPROP 1 LAST VOLTAGE 16V
J 2
(-5900 3450);
DISPLAY 0.617021 (-5900 3450);
PAINT SKYBLUE (-5900 3450);
FORCEPROP 1 LASTPIN (-5850 3350) $PN 2
J 2
(-5860 3330);
DISPLAY 0.617021 (-5860 3330);
PAINT ORANGE (-5860 3330);
FORCEPROP 1 LASTPIN (-5850 3550) $PN 1
J 2
(-5860 3530);
DISPLAY 0.617021 (-5860 3530);
PAINT ORANGE (-5860 3530);
FORCEPROP 1 LAST VALUE 0.220UF
J 2
(-5900 3500);
DISPLAY 0.617021 (-5900 3500);
PAINT SKYBLUE (-5900 3500);
FORCEPROP 1 LAST PART_NUMBER A36096-104
J 2
(-5900 3300);
DISPLAY 0.617021 (-5900 3300);
PAINT BLUE (-5900 3300);
FORCEPROP 2 LAST ROOM PVCCIN_CPU0_PWR_VR
J 0
(-5925 3600);
DISPLAY 1.361702 (-5925 3600);
PAINT ORANGE (-5925 3600);
DISPLAY INVISIBLE (-5925 3600);
FORCEPROP 1 LAST PATH I22
J 2
(-5900 3600);
DISPLAY 0.978723 (-5900 3600);
PAINT WHITE (-5900 3600);
DISPLAY INVISIBLE (-5900 3600);
FORCEPROP 2 LAST NO_XNET_CONNECTION 1
J 0
(-5900 3650);
PAINT MONO (-5900 3650);
DISPLAY INVISIBLE (-5900 3650);
FORCEPROP 2 LAST SEC 1
J 0
(-5900 3650);
DISPLAY 0.680851 (-5900 3650);
PAINT MONO (-5900 3650);
DISPLAY INVISIBLE (-5900 3650);
FORCEPROP 0 LAST SPOF TRUE
J 0
(-5900 3650);
DISPLAY 1.021277 (-5900 3650);
PAINT ORANGE (-5900 3650);
DISPLAY INVISIBLE (-5900 3650);
FORCEPROP 2 LAST SEC_TYPE 0402
J 0
(-5900 3650);
DISPLAY 1.021277 (-5900 3650);
PAINT ORANGE (-5900 3650);
DISPLAY INVISIBLE (-5900 3650);
FORCEPROP 2 LAST CDS_LIB mstr_discrete
J 0
(-5850 3450);
PAINT ORANGE (-5850 3450);
DISPLAY INVISIBLE (-5850 3450);
FORCEPROP 2 LAST CDS_LOCATION C4E17
J 2
(-5900 3550);
DISPLAY 0.617021 (-5900 3550);
PAINT AQUA (-5900 3550);
DISPLAY INVISIBLE (-5900 3550);
FORCEADD CAP..1
(-5100 1425);
FORCEPROP 1 LAST PACK_TYPE 0402
J 0
(-5050 1225);
DISPLAY 0.617021 (-5050 1225);
PAINT SKYBLUE (-5050 1225);
FORCEPROP 1 LAST LOCATION C4E27
J 0
(-5050 1525);
DISPLAY 0.617021 (-5050 1525);
PAINT AQUA (-5050 1525);
FORCEPROP 1 LASTPIN (-5100 1325) $PN 2
J 0
(-5090 1305);
DISPLAY 0.617021 (-5090 1305);
PAINT ORANGE (-5090 1305);
FORCEPROP 1 LAST MATERIAL X7R
J 0
(-5050 1325);
DISPLAY 0.617021 (-5050 1325);
PAINT SKYBLUE (-5050 1325);
FORCEPROP 1 LASTPIN (-5100 1525) $PN 1
J 0
(-5090 1505);
DISPLAY 0.617021 (-5090 1505);
PAINT ORANGE (-5090 1505);
FORCEPROP 1 LAST VALUE 0.22UF
J 0
(-5050 1475);
DISPLAY 0.617021 (-5050 1475);
PAINT SKYBLUE (-5050 1475);
FORCEPROP 1 LAST TOLERANCE 10%
J 0
(-5050 1375);
DISPLAY 0.617021 (-5050 1375);
PAINT SKYBLUE (-5050 1375);
FORCEPROP 1 LAST PART_NUMBER A36096-155
J 0
(-5050 1275);
DISPLAY 0.617021 (-5050 1275);
PAINT BLUE (-5050 1275);
FORCEPROP 1 LAST VOLTAGE 16V
J 0
(-5050 1425);
DISPLAY 0.617021 (-5050 1425);
PAINT SKYBLUE (-5050 1425);
FORCEPROP 2 LAST ROOM PVCCIN_CPU0_PWR_VR
J 0
(-5050 1575);
DISPLAY 1.361702 (-5050 1575);
PAINT ORANGE (-5050 1575);
DISPLAY INVISIBLE (-5050 1575);
FORCEPROP 1 LAST PATH I24
J 0
(-5050 1575);
DISPLAY 0.978723 (-5050 1575);
PAINT WHITE (-5050 1575);
DISPLAY INVISIBLE (-5050 1575);
FORCEPROP 2 LAST SEC 1
J 0
(-5050 1625);
DISPLAY 0.680851 (-5050 1625);
PAINT MONO (-5050 1625);
DISPLAY INVISIBLE (-5050 1625);
FORCEPROP 2 LAST SEC_TYPE 0402
J 0
(-5050 1625);
DISPLAY 1.021277 (-5050 1625);
PAINT ORANGE (-5050 1625);
DISPLAY INVISIBLE (-5050 1625);
FORCEPROP 2 LAST CDS_LIB mstr_discrete
J 0
(-5100 1425);
PAINT ORANGE (-5100 1425);
DISPLAY INVISIBLE (-5100 1425);
FORCEADD CAP_A..1
R 2
(-5225 1450);
FORCEPROP 1 LAST PART_NUMBER D97712-004
J 2
(-5275 1300);
DISPLAY 0.617021 (-5275 1300);
PAINT BLUE (-5275 1300);
FORCEPROP 1 LAST PACK_TYPE 0402V
J 2
(-5275 1250);
DISPLAY 0.617021 (-5275 1250);
PAINT SKYBLUE (-5275 1250);
FORCEPROP 1 LAST LOCATION C4E25
J 2
(-5275 1550);
DISPLAY 0.617021 (-5275 1550);
PAINT AQUA (-5275 1550);
FORCEPROP 1 LASTPIN (-5225 1550) $PN 1
J 2
(-5235 1530);
DISPLAY 0.617021 (-5235 1530);
PAINT ORANGE (-5235 1530);
FORCEPROP 1 LAST TOLERANCE 10%
J 2
(-5275 1400);
DISPLAY 0.617021 (-5275 1400);
PAINT SKYBLUE (-5275 1400);
FORCEPROP 1 LAST MATERIAL X6S
J 2
(-5275 1350);
DISPLAY 0.617021 (-5275 1350);
PAINT SKYBLUE (-5275 1350);
FORCEPROP 1 LASTPIN (-5225 1350) $PN 2
J 2
(-5235 1330);
DISPLAY 0.617021 (-5235 1330);
PAINT ORANGE (-5235 1330);
FORCEPROP 1 LAST VOLTAGE 6.3V
J 2
(-5275 1450);
DISPLAY 0.617021 (-5275 1450);
PAINT SKYBLUE (-5275 1450);
FORCEPROP 1 LAST VALUE 1.0UF
J 2
(-5275 1500);
DISPLAY 0.617021 (-5275 1500);
PAINT SKYBLUE (-5275 1500);
FORCEPROP 2 LAST CDS_SEC 1
J 0
(-5275 1600);
PAINT ORANGE (-5275 1600);
DISPLAY INVISIBLE (-5275 1600);
FORCEPROP 2 LAST ROOM PVCCIN_CPU0_PWR_VR
J 0
(-5275 1600);
DISPLAY 1.361702 (-5275 1600);
PAINT ORANGE (-5275 1600);
DISPLAY INVISIBLE (-5275 1600);
FORCEPROP 1 LAST PATH I25
J 2
(-5275 1600);
DISPLAY 0.978723 (-5275 1600);
PAINT WHITE (-5275 1600);
DISPLAY INVISIBLE (-5275 1600);
FORCEPROP 2 LAST SEC_TYPE 0402V
J 0
(-5275 1650);
DISPLAY 1.021277 (-5275 1650);
PAINT ORANGE (-5275 1650);
DISPLAY INVISIBLE (-5275 1650);
FORCEPROP 2 LAST SEC 1
J 0
(-5275 1650);
DISPLAY 0.680851 (-5275 1650);
PAINT MONO (-5275 1650);
DISPLAY INVISIBLE (-5275 1650);
FORCEPROP 2 LAST CDS_LIB dev_discrete
J 0
(-5225 1450);
PAINT ORANGE (-5225 1450);
DISPLAY INVISIBLE (-5225 1450);
FORCEADD PVCCIN_CPU0..1
(-575 1000);
FORCEPROP 3 LASTPIN (-575 950) SIG_NAME PVCCIN_CPU0\g
J 0
(-565 960);
DISPLAY 0.659574 (-565 960);
PAINT MONO (-565 960);
DISPLAY INVISIBLE (-565 960);
FORCEPROP 1 LAST VOLTAGE 2.0V
J 0
(-620 957);
DISPLAY 0.340426 (-620 957);
PAINT SKYBLUE (-620 957);
DISPLAY INVISIBLE (-620 957);
FORCEPROP 1 LAST BODY_TYPE PLUMBING
J 0
(-620 957);
DISPLAY 0.340426 (-620 957);
PAINT GREEN (-620 957);
DISPLAY INVISIBLE (-620 957);
FORCEPROP 2 LAST CDS_LIB mstr_symbols
J 0
(-575 1000);
PAINT ORANGE (-575 1000);
DISPLAY INVISIBLE (-575 1000);
FORCEPROP 1 LAST HDL_POWER PVCCIN_CPU0
J 1
(-575 1050);
DISPLAY 0.872340 (-575 1050);
PAINT GREEN (-575 1050);
DISPLAY INVISIBLE (-575 1050);
FORCEPROP 1 LAST PATH I26
J 0
(-525 1025);
DISPLAY 0.872340 (-525 1025);
PAINT AQUA (-525 1025);
DISPLAY INVISIBLE (-525 1025);
FORCEADD CAP_A..1
(-875 650);
FORCEPROP 1 LAST MATERIAL X6S
J 0
(-825 550);
DISPLAY 0.617021 (-825 550);
PAINT SKYBLUE (-825 550);
FORCEPROP 1 LAST VALUE 22.0UF
J 0
(-825 700);
DISPLAY 0.617021 (-825 700);
PAINT SKYBLUE (-825 700);
FORCEPROP 1 LAST PART_NUMBER E15431-004
J 0
(-825 500);
DISPLAY 0.617021 (-825 500);
PAINT BLUE (-825 500);
FORCEPROP 1 LAST VOLTAGE 4V
J 0
(-825 650);
DISPLAY 0.617021 (-825 650);
PAINT SKYBLUE (-825 650);
FORCEPROP 1 LAST TOLERANCE 20%
J 0
(-825 600);
DISPLAY 0.617021 (-825 600);
PAINT SKYBLUE (-825 600);
FORCEPROP 1 LAST PACK_TYPE 0603V
J 0
(-825 450);
DISPLAY 0.617021 (-825 450);
PAINT SKYBLUE (-825 450);
FORCEPROP 1 LASTPIN (-875 750) $PN 1
J 0
(-865 730);
DISPLAY 0.617021 (-865 730);
PAINT ORANGE (-865 730);
FORCEPROP 1 LAST LOCATION C4E11
J 0
(-825 750);
DISPLAY 0.617021 (-825 750);
PAINT AQUA (-825 750);
FORCEPROP 1 LASTPIN (-875 550) $PN 2
J 0
(-865 530);
DISPLAY 0.617021 (-865 530);
PAINT ORANGE (-865 530);
FORCEPROP 2 LAST CDS_LIB dev_discrete
J 0
(-875 650);
PAINT ORANGE (-875 650);
DISPLAY INVISIBLE (-875 650);
FORCEPROP 2 LAST ROOM PVCCIN_CPU0_PWR_VR
J 0
(-825 800);
DISPLAY 1.446809 (-825 800);
PAINT MONO (-825 800);
DISPLAY INVISIBLE (-825 800);
FORCEPROP 1 LAST PATH I27
J 0
(-825 800);
DISPLAY 0.978723 (-825 800);
PAINT WHITE (-825 800);
DISPLAY INVISIBLE (-825 800);
FORCEPROP 2 LAST CDS_SEC 1
J 0
(-825 800);
PAINT ORANGE (-825 800);
DISPLAY INVISIBLE (-825 800);
FORCEPROP 2 LAST BOM_COST PROC_VRD_VCCIN_CPU0
J 0
(-825 800);
DISPLAY 1.446809 (-825 800);
PAINT MONO (-825 800);
DISPLAY INVISIBLE (-825 800);
FORCEPROP 2 LAST CDS_LOCATION C4E11
J 0
(-825 750);
DISPLAY 0.617021 (-825 750);
PAINT AQUA (-825 750);
DISPLAY INVISIBLE (-825 750);
FORCEPROP 2 LAST SEC_TYPE 0603V
J 0
(-820 850);
DISPLAY 1.021277 (-820 850);
PAINT ORANGE (-820 850);
DISPLAY INVISIBLE (-820 850);
FORCEPROP 2 LAST SEC 1
J 0
(-820 850);
DISPLAY 0.680851 (-820 850);
PAINT MONO (-820 850);
DISPLAY INVISIBLE (-820 850);
FORCEADD GND..1
(-575 350);
FORCEPROP 3 LASTPIN (-575 400) SIG_NAME GND\g
J 0
(-565 410);
DISPLAY 0.659574 (-565 410);
PAINT MONO (-565 410);
DISPLAY INVISIBLE (-565 410);
FORCEPROP 1 LAST HDL_POWER GND
J 0
(-575 500);
DISPLAY 1.723404 (-575 500);
PAINT GREEN (-575 500);
DISPLAY INVISIBLE (-575 500);
FORCEPROP 1 LAST VOLTAGE 0
J 0
(-575 350);
PAINT SKYBLUE (-575 350);
DISPLAY INVISIBLE (-575 350);
FORCEPROP 2 LAST CDS_LIB mstr_symbols
J 0
(-575 350);
PAINT ORANGE (-575 350);
DISPLAY INVISIBLE (-575 350);
FORCEPROP 1 LAST PATH I28
J 0
(-500 350);
DISPLAY 0.872340 (-500 350);
PAINT AQUA (-500 350);
DISPLAY INVISIBLE (-500 350);
FORCEPROP 1 LAST SIZE 1B
J 0
(-500 300);
DISPLAY 1.723404 (-500 300);
PAINT GREEN (-500 300);
DISPLAY INVISIBLE (-500 300);
FORCEPROP 1 LAST BODY_TYPE PLUMBING
J 0
(-620 307);
DISPLAY 0.340426 (-620 307);
PAINT GREEN (-620 307);
DISPLAY INVISIBLE (-620 307);
FORCEPROP 2 LAST BOM_COST PROC_VRD_VCCIN_CPU0
J 0
(-950 425);
DISPLAY 1.446809 (-950 425);
PAINT MONO (-950 425);
DISPLAY INVISIBLE (-950 425);
FORCEPROP 2 LAST ROOM PVCCIN_CPU0_PWR_VR
J 0
(-1125 425);
DISPLAY 1.936170 (-1125 425);
PAINT ORANGE (-1125 425);
DISPLAY INVISIBLE (-1125 425);
FORCEADD INDUCTOR..1
(-1700 925);
FORCEPROP 1 LAST MATERIAL IND
J 0
(-1660 815);
DISPLAY 0.617021 (-1660 815);
PAINT SKYBLUE (-1660 815);
FORCEPROP 1 LAST LOCATION L4D3
J 0
(-1800 975);
DISPLAY 0.617021 (-1800 975);
PAINT AQUA (-1800 975);
FORCEPROP 1 LASTPIN (-1800 925) $PN 1
J 0
(-1800 935);
DISPLAY 0.617021 (-1800 935);
PAINT WHITE (-1800 935);
FORCEPROP 1 LAST VALUE 0.12UH
J 2
(-1705 815);
DISPLAY 0.617021 (-1705 815);
PAINT SKYBLUE (-1705 815);
FORCEPROP 1 LAST PACK_TYPE SM
J 0
(-1535 815);
DISPLAY 0.617021 (-1535 815);
PAINT SKYBLUE (-1535 815);
FORCEPROP 1 LASTPIN (-1600 925) $PN 2
J 2
(-1590 935);
DISPLAY 0.617021 (-1590 935);
PAINT WHITE (-1590 935);
FORCEPROP 1 LAST PART_NUMBER D92183-034
J 0
(-1825 875);
DISPLAY 0.617021 (-1825 875);
PAINT BLUE (-1825 875);
FORCEPROP 2 LAST CDS_LOCATION L4D3
J 0
(-1800 975);
DISPLAY 0.617021 (-1800 975);
PAINT AQUA (-1800 975);
DISPLAY INVISIBLE (-1800 975);
FORCEPROP 2 LAST CDS_LIB mstr_discrete
J 0
(-1700 925);
PAINT ORANGE (-1700 925);
DISPLAY INVISIBLE (-1700 925);
FORCEPROP 2 LAST ROOM PVCCIN_CPU0_PWR_VR
J 0
(-1800 1025);
DISPLAY 1.361702 (-1800 1025);
PAINT ORANGE (-1800 1025);
DISPLAY INVISIBLE (-1800 1025);
FORCEPROP 1 LAST PATH I29
J 0
(-1800 1075);
DISPLAY 0.978723 (-1800 1075);
PAINT ORANGE (-1800 1075);
DISPLAY INVISIBLE (-1800 1075);
FORCEPROP 2 LAST $SEC 1
J 0
(-1800 1125);
PAINT MONO (-1800 1125);
DISPLAY INVISIBLE (-1800 1125);
FORCEPROP 2 LAST CDS_SEC 1
J 0
(-1800 1125);
PAINT MONO (-1800 1125);
DISPLAY INVISIBLE (-1800 1125);
FORCEADD OFFPAGE..2
(-1700 4000);
FORCEPROP 2 LAST $XR2 204 
J 0
(-1271 4000);
DISPLAY 0.638298 (-1271 4000);
PAINT MONO (-1271 4000);
FORCEPROP 2 LAST $XR1 203 
J 0
(-1391 4000);
DISPLAY 0.638298 (-1391 4000);
PAINT MONO (-1391 4000);
FORCEPROP 2 LAST $XR3 201 
J 0
(-1151 4000);
DISPLAY 0.638298 (-1151 4000);
PAINT MONO (-1151 4000);
FORCEPROP 2 LAST $XR0 202 
J 0
(-1511 4000);
DISPLAY 0.638298 (-1511 4000);
PAINT MONO (-1511 4000);
FORCEPROP 2 LAST BOM_COST PROC_VRD_VCCIN_CPU0
J 0
(-1500 4050);
DISPLAY 1.446809 (-1500 4050);
PAINT MONO (-1500 4050);
DISPLAY INVISIBLE (-1500 4050);
FORCEPROP 1 LAST OFFPAGE TRUE
J 0
(-1375 3875);
DISPLAY 1.723404 (-1375 3875);
PAINT GREEN (-1375 3875);
DISPLAY INVISIBLE (-1375 3875);
FORCEPROP 2 LAST CDS_LIB mstr_standard
J 0
(-1700 4000);
PAINT ORANGE (-1700 4000);
DISPLAY INVISIBLE (-1700 4000);
FORCEPROP 2 LAST PATH I3
J 0
(-1520 4075);
DISPLAY 1.021277 (-1520 4075);
PAINT ORANGE (-1520 4075);
DISPLAY INVISIBLE (-1520 4075);
FORCEPROP 1 LAST COMMENT_BODY TRUE
J 0
(-1745 3905);
DISPLAY 1.723404 (-1745 3905);
PAINT GREEN (-1745 3905);
DISPLAY INVISIBLE (-1745 3905);
FORCEPROP 2 LAST ROOM PVCCIN_CPU0_PWR_VR
J 0
(-2100 4075);
DISPLAY 1.936170 (-2100 4075);
PAINT ORANGE (-2100 4075);
DISPLAY INVISIBLE (-2100 4075);
FORCEADD GND..1
(-2800 525);
FORCEPROP 3 LASTPIN (-2800 575) SIG_NAME GND\g
J 0
(-2790 585);
DISPLAY 0.659574 (-2790 585);
PAINT MONO (-2790 585);
DISPLAY INVISIBLE (-2790 585);
FORCEPROP 1 LAST HDL_POWER GND
J 0
(-2800 675);
DISPLAY 1.723404 (-2800 675);
PAINT GREEN (-2800 675);
DISPLAY INVISIBLE (-2800 675);
FORCEPROP 1 LAST PATH I30
J 0
(-2725 525);
DISPLAY 0.872340 (-2725 525);
PAINT AQUA (-2725 525);
DISPLAY INVISIBLE (-2725 525);
FORCEPROP 2 LAST CDS_LIB mstr_symbols
J 0
(-2800 525);
PAINT ORANGE (-2800 525);
DISPLAY INVISIBLE (-2800 525);
FORCEPROP 1 LAST VOLTAGE 0
J 0
(-2800 525);
PAINT SKYBLUE (-2800 525);
DISPLAY INVISIBLE (-2800 525);
FORCEPROP 1 LAST SIZE 1B
J 0
(-2725 475);
DISPLAY 1.723404 (-2725 475);
PAINT GREEN (-2725 475);
DISPLAY INVISIBLE (-2725 475);
FORCEPROP 1 LAST BODY_TYPE PLUMBING
J 0
(-2845 482);
DISPLAY 0.340426 (-2845 482);
PAINT GREEN (-2845 482);
DISPLAY INVISIBLE (-2845 482);
FORCEPROP 2 LAST BOM_COST PROC_VRD_VCCIN_CPU0
J 0
(-3175 600);
DISPLAY 1.446809 (-3175 600);
PAINT MONO (-3175 600);
DISPLAY INVISIBLE (-3175 600);
FORCEPROP 2 LAST ROOM PVCCIN_CPU0_PWR_VR
J 0
(-3350 600);
DISPLAY 1.936170 (-3350 600);
PAINT ORANGE (-3350 600);
DISPLAY INVISIBLE (-3350 600);
FORCEADD CAP..1
R 2
(-5950 825);
FORCEPROP 1 LAST PART_NUMBER A36096-104
J 2
(-6000 675);
DISPLAY 0.617021 (-6000 675);
PAINT BLUE (-6000 675);
FORCEPROP 1 LAST MATERIAL X7R
J 2
(-6000 725);
DISPLAY 0.617021 (-6000 725);
PAINT SKYBLUE (-6000 725);
FORCEPROP 1 LAST VOLTAGE 16V
J 2
(-6000 825);
DISPLAY 0.617021 (-6000 825);
PAINT SKYBLUE (-6000 825);
FORCEPROP 1 LAST PACK_TYPE 0402
J 2
(-6000 625);
DISPLAY 0.617021 (-6000 625);
PAINT SKYBLUE (-6000 625);
FORCEPROP 1 LAST TOLERANCE 10%
J 2
(-6000 775);
DISPLAY 0.617021 (-6000 775);
PAINT SKYBLUE (-6000 775);
FORCEPROP 1 LAST VALUE 0.220UF
J 2
(-6000 875);
DISPLAY 0.617021 (-6000 875);
PAINT SKYBLUE (-6000 875);
FORCEPROP 1 LAST LOCATION C4D50
J 2
(-6000 925);
DISPLAY 0.617021 (-6000 925);
PAINT AQUA (-6000 925);
FORCEPROP 1 LASTPIN (-5950 925) $PN 1
J 2
(-5960 905);
DISPLAY 0.617021 (-5960 905);
PAINT ORANGE (-5960 905);
FORCEPROP 1 LASTPIN (-5950 725) $PN 2
J 2
(-5960 705);
DISPLAY 0.617021 (-5960 705);
PAINT ORANGE (-5960 705);
FORCEPROP 1 LAST PATH I32
J 2
(-6000 975);
DISPLAY 0.978723 (-6000 975);
PAINT WHITE (-6000 975);
DISPLAY INVISIBLE (-6000 975);
FORCEPROP 2 LAST CDS_LIB mstr_discrete
J 0
(-5950 825);
PAINT ORANGE (-5950 825);
DISPLAY INVISIBLE (-5950 825);
FORCEPROP 2 LAST ROOM PVCCIN_CPU0_PWR_VR
J 0
(-6000 975);
DISPLAY 1.361702 (-6000 975);
PAINT ORANGE (-6000 975);
DISPLAY INVISIBLE (-6000 975);
FORCEPROP 2 LAST SEC_TYPE 0402
J 0
(-6000 1025);
DISPLAY 1.021277 (-6000 1025);
PAINT ORANGE (-6000 1025);
DISPLAY INVISIBLE (-6000 1025);
FORCEPROP 0 LAST SPOF TRUE
J 0
(-6000 1025);
DISPLAY 1.021277 (-6000 1025);
PAINT ORANGE (-6000 1025);
DISPLAY INVISIBLE (-6000 1025);
FORCEPROP 2 LAST SEC 1
J 0
(-6000 1025);
DISPLAY 0.680851 (-6000 1025);
PAINT MONO (-6000 1025);
DISPLAY INVISIBLE (-6000 1025);
FORCEPROP 2 LAST NO_XNET_CONNECTION 1
J 0
(-6000 1025);
PAINT MONO (-6000 1025);
DISPLAY INVISIBLE (-6000 1025);
FORCEADD RES..1
(-5500 4625);
FORCEPROP 1 LAST LOCATION R6R2
J 0
(-5550 4675);
DISPLAY 0.617021 (-5550 4675);
PAINT AQUA (-5550 4675);
FORCEPROP 1 LAST PART_NUMBER G21796-090
J 0
(-5625 4550);
DISPLAY 0.617021 (-5625 4550);
PAINT BLUE (-5625 4550);
FORCEPROP 1 LASTPIN (-5400 4625) $PN 2
J 0
(-5438 4637);
DISPLAY 0.617021 (-5438 4637);
PAINT ORANGE (-5438 4637);
FORCEPROP 1 LASTPIN (-5600 4625) $PN 1
J 0
(-5588 4637);
DISPLAY 0.617021 (-5588 4637);
PAINT ORANGE (-5588 4637);
FORCEPROP 1 LAST MATERIAL CHIP
J 0
(-5425 4450);
DISPLAY 0.617021 (-5425 4450);
PAINT SKYBLUE (-5425 4450);
FORCEPROP 1 LAST WATTAGE 1/16W
J 2
(-5475 4450);
DISPLAY 0.617021 (-5475 4450);
PAINT SKYBLUE (-5475 4450);
FORCEPROP 1 LAST TOLERANCE 1%
J 0
(-5550 4500);
DISPLAY 0.617021 (-5550 4500);
PAINT SKYBLUE (-5550 4500);
FORCEPROP 1 LAST VALUE 1.0
J 2
(-5600 4500);
DISPLAY 0.617021 (-5600 4500);
PAINT SKYBLUE (-5600 4500);
FORCEPROP 1 LAST PACK_TYPE 0402
J 0
(-5450 4500);
DISPLAY 0.617021 (-5450 4500);
PAINT SKYBLUE (-5450 4500);
FORCEPROP 2 LAST SEC_TYPE 0402
J 0
(-5550 4825);
DISPLAY 1.021277 (-5550 4825);
PAINT ORANGE (-5550 4825);
DISPLAY INVISIBLE (-5550 4825);
FORCEPROP 2 LAST CDS_LIB mstr_discrete
J 0
(-5500 4625);
PAINT ORANGE (-5500 4625);
DISPLAY INVISIBLE (-5500 4625);
FORCEPROP 2 LAST ROOM PVCCIN_CPU0_PWR_VR
J 0
(-5550 4725);
DISPLAY 1.361702 (-5550 4725);
PAINT ORANGE (-5550 4725);
DISPLAY INVISIBLE (-5550 4725);
FORCEPROP 1 LAST PATH I33
J 0
(-5550 4775);
DISPLAY 0.978723 (-5550 4775);
PAINT WHITE (-5550 4775);
DISPLAY INVISIBLE (-5550 4775);
FORCEPROP 2 LAST CDS_LOCATION R6R2
J 0
(-5550 4675);
DISPLAY 0.617021 (-5550 4675);
PAINT AQUA (-5550 4675);
DISPLAY INVISIBLE (-5550 4675);
FORCEPROP 2 LAST SEC 1
J 0
(-5550 4825);
DISPLAY 0.680851 (-5550 4825);
PAINT MONO (-5550 4825);
DISPLAY INVISIBLE (-5550 4825);
FORCEADD CAP..1
(-5750 4025);
FORCEPROP 1 LAST LOCATION C4E10
J 0
(-5700 4125);
DISPLAY 0.617021 (-5700 4125);
PAINT AQUA (-5700 4125);
FORCEPROP 1 LASTPIN (-5750 4125) $PN 1
J 0
(-5740 4105);
DISPLAY 0.617021 (-5740 4105);
PAINT ORANGE (-5740 4105);
FORCEPROP 1 LAST VALUE 1.0UF
J 0
(-5700 4075);
DISPLAY 0.617021 (-5700 4075);
PAINT SKYBLUE (-5700 4075);
FORCEPROP 1 LAST TOLERANCE 10%
J 0
(-5700 3975);
DISPLAY 0.617021 (-5700 3975);
PAINT SKYBLUE (-5700 3975);
FORCEPROP 1 LAST PACK_TYPE 0402
J 0
(-5700 3825);
DISPLAY 0.617021 (-5700 3825);
PAINT SKYBLUE (-5700 3825);
FORCEPROP 1 LAST VOLTAGE 16V
J 0
(-5700 4025);
DISPLAY 0.617021 (-5700 4025);
PAINT SKYBLUE (-5700 4025);
FORCEPROP 1 LASTPIN (-5750 3925) $PN 2
J 0
(-5740 3905);
DISPLAY 0.617021 (-5740 3905);
PAINT ORANGE (-5740 3905);
FORCEPROP 1 LAST MATERIAL X6S
J 0
(-5700 3925);
DISPLAY 0.617021 (-5700 3925);
PAINT SKYBLUE (-5700 3925);
FORCEPROP 1 LAST PART_NUMBER D97712-011
J 0
(-5700 3875);
DISPLAY 0.617021 (-5700 3875);
PAINT BLUE (-5700 3875);
FORCEPROP 2 LAST ROOM PVCCIN_CPU0_PWR_VR
J 0
(-5700 4175);
DISPLAY 1.361702 (-5700 4175);
PAINT ORANGE (-5700 4175);
DISPLAY INVISIBLE (-5700 4175);
FORCEPROP 1 LAST PATH I34
J 0
(-5700 4175);
DISPLAY 0.978723 (-5700 4175);
PAINT WHITE (-5700 4175);
DISPLAY INVISIBLE (-5700 4175);
FORCEPROP 2 LAST CDS_LOCATION C4E10
J 0
(-5700 4125);
DISPLAY 0.617021 (-5700 4125);
PAINT AQUA (-5700 4125);
DISPLAY INVISIBLE (-5700 4125);
FORCEPROP 2 LAST SEC 1
J 0
(-5700 4225);
DISPLAY 0.680851 (-5700 4225);
PAINT MONO (-5700 4225);
DISPLAY INVISIBLE (-5700 4225);
FORCEPROP 2 LAST SEC_TYPE 0402
J 0
(-5700 4225);
DISPLAY 1.021277 (-5700 4225);
PAINT ORANGE (-5700 4225);
DISPLAY INVISIBLE (-5700 4225);
FORCEPROP 2 LAST CDS_LIB mstr_discrete
J 0
(-5750 4025);
PAINT ORANGE (-5750 4025);
DISPLAY INVISIBLE (-5750 4025);
FORCEADD CAP_A..1
(-6050 4025);
FORCEPROP 1 LAST LOCATION C4E20
J 0
(-6000 4125);
DISPLAY 0.617021 (-6000 4125);
PAINT AQUA (-6000 4125);
FORCEPROP 1 LAST TOLERANCE 10%
J 0
(-6000 3975);
DISPLAY 0.617021 (-6000 3975);
PAINT SKYBLUE (-6000 3975);
FORCEPROP 1 LAST VOLTAGE 16V
J 0
(-6000 4025);
DISPLAY 0.617021 (-6000 4025);
PAINT SKYBLUE (-6000 4025);
FORCEPROP 1 LAST MATERIAL X7R
J 0
(-6000 3925);
DISPLAY 0.617021 (-6000 3925);
PAINT SKYBLUE (-6000 3925);
FORCEPROP 1 LAST PACK_TYPE 0402V
J 0
(-6000 3825);
DISPLAY 0.617021 (-6000 3825);
PAINT SKYBLUE (-6000 3825);
FORCEPROP 1 LAST VALUE 0.1UF
J 0
(-6000 4075);
DISPLAY 0.617021 (-6000 4075);
PAINT SKYBLUE (-6000 4075);
FORCEPROP 1 LASTPIN (-6050 3925) $PN 2
J 0
(-6040 3905);
DISPLAY 0.617021 (-6040 3905);
PAINT ORANGE (-6040 3905);
FORCEPROP 1 LASTPIN (-6050 4125) $PN 1
J 0
(-6040 4105);
DISPLAY 0.617021 (-6040 4105);
PAINT ORANGE (-6040 4105);
FORCEPROP 1 LAST PART_NUMBER A36096-030
J 0
(-6000 3875);
DISPLAY 0.617021 (-6000 3875);
PAINT BLUE (-6000 3875);
FORCEPROP 2 LAST ROOM PVCCIN_CPU0_PWR_VR
J 0
(-6000 4175);
DISPLAY 1.361702 (-6000 4175);
PAINT ORANGE (-6000 4175);
DISPLAY INVISIBLE (-6000 4175);
FORCEPROP 1 LAST PATH I35
J 0
(-6000 4175);
DISPLAY 0.978723 (-6000 4175);
PAINT WHITE (-6000 4175);
DISPLAY INVISIBLE (-6000 4175);
FORCEPROP 2 LAST SEC 1
J 0
(-6000 4225);
DISPLAY 0.680851 (-6000 4225);
PAINT MONO (-6000 4225);
DISPLAY INVISIBLE (-6000 4225);
FORCEPROP 2 LAST SEC_TYPE 0402V
J 0
(-6000 4225);
DISPLAY 1.021277 (-6000 4225);
PAINT ORANGE (-6000 4225);
DISPLAY INVISIBLE (-6000 4225);
FORCEPROP 2 LAST CDS_LIB dev_discrete
J 0
(-6050 4025);
PAINT ORANGE (-6050 4025);
DISPLAY INVISIBLE (-6050 4025);
FORCEPROP 2 LAST CDS_SEC 1
J 0
(-6000 4175);
PAINT ORANGE (-6000 4175);
DISPLAY INVISIBLE (-6000 4175);
FORCEPROP 2 LAST CDS_LOCATION C4E20
J 0
(-6000 4125);
DISPLAY 0.617021 (-6000 4125);
PAINT AQUA (-6000 4125);
DISPLAY INVISIBLE (-6000 4125);
FORCEADD CAP..1
(-6325 4050);
FORCEPROP 1 LAST LOCATION C4E19
J 0
(-6275 4150);
DISPLAY 0.617021 (-6275 4150);
PAINT AQUA (-6275 4150);
FORCEPROP 1 LAST VALUE 1.0UF
J 0
(-6275 4100);
DISPLAY 0.617021 (-6275 4100);
PAINT SKYBLUE (-6275 4100);
FORCEPROP 1 LASTPIN (-6325 4150) $PN 1
J 0
(-6315 4130);
DISPLAY 0.617021 (-6315 4130);
PAINT ORANGE (-6315 4130);
FORCEPROP 1 LAST PART_NUMBER D97712-011
J 0
(-6275 3900);
DISPLAY 0.617021 (-6275 3900);
PAINT BLUE (-6275 3900);
FORCEPROP 1 LASTPIN (-6325 3950) $PN 2
J 0
(-6315 3930);
DISPLAY 0.617021 (-6315 3930);
PAINT ORANGE (-6315 3930);
FORCEPROP 1 LAST MATERIAL X6S
J 0
(-6275 3950);
DISPLAY 0.617021 (-6275 3950);
PAINT SKYBLUE (-6275 3950);
FORCEPROP 1 LAST VOLTAGE 16V
J 0
(-6275 4050);
DISPLAY 0.617021 (-6275 4050);
PAINT SKYBLUE (-6275 4050);
FORCEPROP 1 LAST PACK_TYPE 0402
J 0
(-6275 3850);
DISPLAY 0.617021 (-6275 3850);
PAINT SKYBLUE (-6275 3850);
FORCEPROP 1 LAST TOLERANCE 10%
J 0
(-6275 4000);
DISPLAY 0.617021 (-6275 4000);
PAINT SKYBLUE (-6275 4000);
FORCEPROP 2 LAST SEC_TYPE 0402
J 0
(-6275 4250);
DISPLAY 1.021277 (-6275 4250);
PAINT ORANGE (-6275 4250);
DISPLAY INVISIBLE (-6275 4250);
FORCEPROP 2 LAST SEC 1
J 0
(-6275 4250);
DISPLAY 0.680851 (-6275 4250);
PAINT MONO (-6275 4250);
DISPLAY INVISIBLE (-6275 4250);
FORCEPROP 2 LAST CDS_LOCATION C4E19
J 0
(-6275 4150);
DISPLAY 0.617021 (-6275 4150);
PAINT AQUA (-6275 4150);
DISPLAY INVISIBLE (-6275 4150);
FORCEPROP 1 LAST PATH I36
J 0
(-6275 4200);
DISPLAY 0.978723 (-6275 4200);
PAINT WHITE (-6275 4200);
DISPLAY INVISIBLE (-6275 4200);
FORCEPROP 2 LAST ROOM PVCCIN_CPU0_PWR_VR
J 0
(-6275 4200);
DISPLAY 1.361702 (-6275 4200);
PAINT ORANGE (-6275 4200);
DISPLAY INVISIBLE (-6275 4200);
FORCEPROP 2 LAST CDS_LIB mstr_discrete
J 0
(-6325 4050);
PAINT ORANGE (-6325 4050);
DISPLAY INVISIBLE (-6325 4050);
FORCEADD CAP..1
(-6600 4050);
FORCEPROP 1 LAST PACK_TYPE 0805
J 0
(-6550 3850);
DISPLAY 0.617021 (-6550 3850);
PAINT SKYBLUE (-6550 3850);
FORCEPROP 1 LAST PART_NUMBER C95333-007
J 0
(-6550 3900);
DISPLAY 0.617021 (-6550 3900);
PAINT BLUE (-6550 3900);
FORCEPROP 1 LAST MATERIAL X6S
J 0
(-6550 3950);
DISPLAY 0.617021 (-6550 3950);
PAINT SKYBLUE (-6550 3950);
FORCEPROP 1 LAST TOLERANCE 10%
J 0
(-6550 4000);
DISPLAY 0.617021 (-6550 4000);
PAINT SKYBLUE (-6550 4000);
FORCEPROP 1 LAST VOLTAGE 16V
J 0
(-6550 4050);
DISPLAY 0.617021 (-6550 4050);
PAINT SKYBLUE (-6550 4050);
FORCEPROP 1 LAST VALUE 10UF
J 0
(-6550 4100);
DISPLAY 0.617021 (-6550 4100);
PAINT SKYBLUE (-6550 4100);
FORCEPROP 1 LAST LOCATION C6R11
J 0
(-6550 4150);
DISPLAY 0.617021 (-6550 4150);
PAINT AQUA (-6550 4150);
FORCEPROP 1 LASTPIN (-6600 4150) $PN 1
J 0
(-6590 4130);
DISPLAY 0.617021 (-6590 4130);
PAINT ORANGE (-6590 4130);
FORCEPROP 1 LASTPIN (-6600 3950) $PN 2
J 0
(-6590 3930);
DISPLAY 0.617021 (-6590 3930);
PAINT ORANGE (-6590 3930);
FORCEPROP 2 LAST SEC_TYPE 0805
J 0
(-6550 4250);
DISPLAY 1.021277 (-6550 4250);
PAINT ORANGE (-6550 4250);
DISPLAY INVISIBLE (-6550 4250);
FORCEPROP 2 LAST SEC 1
J 0
(-6550 4250);
DISPLAY 0.680851 (-6550 4250);
PAINT MONO (-6550 4250);
DISPLAY INVISIBLE (-6550 4250);
FORCEPROP 2 LAST CDS_LOCATION C6R11
J 0
(-6550 4150);
DISPLAY 0.617021 (-6550 4150);
PAINT AQUA (-6550 4150);
DISPLAY INVISIBLE (-6550 4150);
FORCEPROP 1 LAST PATH I37
J 0
(-6550 4200);
DISPLAY 0.978723 (-6550 4200);
PAINT WHITE (-6550 4200);
DISPLAY INVISIBLE (-6550 4200);
FORCEPROP 2 LAST ROOM PVCCIN_CPU0_PWR_VR
J 0
(-6550 4200);
DISPLAY 1.361702 (-6550 4200);
PAINT ORANGE (-6550 4200);
DISPLAY INVISIBLE (-6550 4200);
FORCEPROP 2 LAST CDS_LIB mstr_discrete
J 0
(-6600 4050);
PAINT ORANGE (-6600 4050);
DISPLAY INVISIBLE (-6600 4050);
FORCEADD CAP..1
(-6900 4075);
FORCEPROP 1 LASTPIN (-6900 3975) $PN 2
J 0
(-6890 3955);
DISPLAY 0.617021 (-6890 3955);
PAINT ORANGE (-6890 3955);
FORCEPROP 1 LAST MATERIAL X6S
J 0
(-6850 3975);
DISPLAY 0.617021 (-6850 3975);
PAINT SKYBLUE (-6850 3975);
FORCEPROP 1 LAST PART_NUMBER C95333-007
J 0
(-6850 3925);
DISPLAY 0.617021 (-6850 3925);
PAINT BLUE (-6850 3925);
FORCEPROP 1 LAST PACK_TYPE 0805
J 0
(-6850 3875);
DISPLAY 0.617021 (-6850 3875);
PAINT SKYBLUE (-6850 3875);
FORCEPROP 1 LAST LOCATION C6P13
J 0
(-6850 4175);
DISPLAY 0.617021 (-6850 4175);
PAINT AQUA (-6850 4175);
FORCEPROP 1 LASTPIN (-6900 4175) $PN 1
J 0
(-6890 4155);
DISPLAY 0.617021 (-6890 4155);
PAINT ORANGE (-6890 4155);
FORCEPROP 1 LAST VALUE 10UF
J 0
(-6850 4125);
DISPLAY 0.617021 (-6850 4125);
PAINT SKYBLUE (-6850 4125);
FORCEPROP 1 LAST VOLTAGE 16V
J 0
(-6850 4075);
DISPLAY 0.617021 (-6850 4075);
PAINT SKYBLUE (-6850 4075);
FORCEPROP 1 LAST TOLERANCE 10%
J 0
(-6850 4025);
DISPLAY 0.617021 (-6850 4025);
PAINT SKYBLUE (-6850 4025);
FORCEPROP 2 LAST ROOM PVCCIN_CPU0_PWR_VR
J 0
(-6850 4225);
DISPLAY 1.361702 (-6850 4225);
PAINT ORANGE (-6850 4225);
DISPLAY INVISIBLE (-6850 4225);
FORCEPROP 2 LAST SEC 1
J 0
(-6850 4275);
DISPLAY 0.680851 (-6850 4275);
PAINT MONO (-6850 4275);
DISPLAY INVISIBLE (-6850 4275);
FORCEPROP 2 LAST CDS_LOCATION C6P13
J 0
(-6850 4175);
DISPLAY 0.617021 (-6850 4175);
PAINT AQUA (-6850 4175);
DISPLAY INVISIBLE (-6850 4175);
FORCEPROP 2 LAST SEC_TYPE 0805
J 0
(-6850 4275);
DISPLAY 1.021277 (-6850 4275);
PAINT ORANGE (-6850 4275);
DISPLAY INVISIBLE (-6850 4275);
FORCEPROP 1 LAST PATH I38
J 0
(-6850 4225);
DISPLAY 0.978723 (-6850 4225);
PAINT WHITE (-6850 4225);
DISPLAY INVISIBLE (-6850 4225);
FORCEPROP 2 LAST CDS_LIB mstr_discrete
J 0
(-6900 4075);
PAINT ORANGE (-6900 4075);
DISPLAY INVISIBLE (-6900 4075);
FORCEADD RES..1
(-5625 1975);
FORCEPROP 1 LAST WATTAGE 1/16W
J 2
(-5600 1800);
DISPLAY 0.617021 (-5600 1800);
PAINT SKYBLUE (-5600 1800);
FORCEPROP 1 LAST LOCATION R6R6
J 0
(-5675 2025);
DISPLAY 0.617021 (-5675 2025);
PAINT AQUA (-5675 2025);
FORCEPROP 1 LASTPIN (-5525 1975) $PN 2
J 0
(-5563 1987);
DISPLAY 0.617021 (-5563 1987);
PAINT ORANGE (-5563 1987);
FORCEPROP 1 LAST MATERIAL CHIP
J 0
(-5550 1800);
DISPLAY 0.617021 (-5550 1800);
PAINT SKYBLUE (-5550 1800);
FORCEPROP 1 LAST PACK_TYPE 0402
J 0
(-5575 1850);
DISPLAY 0.617021 (-5575 1850);
PAINT SKYBLUE (-5575 1850);
FORCEPROP 1 LAST PART_NUMBER G21796-090
J 0
(-5750 1900);
DISPLAY 0.617021 (-5750 1900);
PAINT BLUE (-5750 1900);
FORCEPROP 1 LASTPIN (-5725 1975) $PN 1
J 0
(-5713 1987);
DISPLAY 0.617021 (-5713 1987);
PAINT ORANGE (-5713 1987);
FORCEPROP 1 LAST VALUE 1.0
J 2
(-5725 1850);
DISPLAY 0.617021 (-5725 1850);
PAINT SKYBLUE (-5725 1850);
FORCEPROP 1 LAST TOLERANCE 1%
J 0
(-5675 1850);
DISPLAY 0.617021 (-5675 1850);
PAINT SKYBLUE (-5675 1850);
FORCEPROP 2 LAST SEC_TYPE 0402
J 0
(-5675 2175);
DISPLAY 1.021277 (-5675 2175);
PAINT ORANGE (-5675 2175);
DISPLAY INVISIBLE (-5675 2175);
FORCEPROP 2 LAST SEC 1
J 0
(-5675 2175);
DISPLAY 0.680851 (-5675 2175);
PAINT MONO (-5675 2175);
DISPLAY INVISIBLE (-5675 2175);
FORCEPROP 1 LAST PATH I39
J 0
(-5675 2125);
DISPLAY 0.978723 (-5675 2125);
PAINT WHITE (-5675 2125);
DISPLAY INVISIBLE (-5675 2125);
FORCEPROP 2 LAST ROOM PVCCIN_CPU0_PWR_VR
J 0
(-5675 2075);
DISPLAY 1.361702 (-5675 2075);
PAINT ORANGE (-5675 2075);
DISPLAY INVISIBLE (-5675 2075);
FORCEPROP 2 LAST CDS_LIB mstr_discrete
J 0
(-5625 1975);
PAINT ORANGE (-5625 1975);
DISPLAY INVISIBLE (-5625 1975);
FORCEADD PVCCIN_CPU0..1
(-1075 3675);
FORCEPROP 3 LASTPIN (-1075 3625) SIG_NAME PVCCIN_CPU0\g
J 0
(-1065 3635);
DISPLAY 0.659574 (-1065 3635);
PAINT MONO (-1065 3635);
DISPLAY INVISIBLE (-1065 3635);
FORCEPROP 1 LAST HDL_POWER PVCCIN_CPU0
J 1
(-1075 3725);
DISPLAY 0.872340 (-1075 3725);
PAINT GREEN (-1075 3725);
DISPLAY INVISIBLE (-1075 3725);
FORCEPROP 2 LAST ROOM PVCCIN_CPU0_PWR_VR
J 0
(-1075 3775);
DISPLAY 1.936170 (-1075 3775);
PAINT ORANGE (-1075 3775);
DISPLAY INVISIBLE (-1075 3775);
FORCEPROP 1 LAST PATH I4
J 0
(-1025 3700);
DISPLAY 0.872340 (-1025 3700);
PAINT AQUA (-1025 3700);
DISPLAY INVISIBLE (-1025 3700);
FORCEPROP 1 LAST BODY_TYPE PLUMBING
J 0
(-1120 3632);
DISPLAY 0.340426 (-1120 3632);
PAINT GREEN (-1120 3632);
DISPLAY INVISIBLE (-1120 3632);
FORCEPROP 2 LAST CDS_LIB mstr_symbols
J 0
(-1075 3675);
PAINT ORANGE (-1075 3675);
DISPLAY INVISIBLE (-1075 3675);
FORCEPROP 2 LAST BOM_COST PROC_SOCKET 
J 0
(-1075 3775);
DISPLAY 1.446809 (-1075 3775);
PAINT MONO (-1075 3775);
DISPLAY INVISIBLE (-1075 3775);
FORCEPROP 1 LAST VOLTAGE 2.0V
J 0
(-1120 3632);
DISPLAY 0.340426 (-1120 3632);
PAINT SKYBLUE (-1120 3632);
DISPLAY INVISIBLE (-1120 3632);
FORCEADD OFFPAGE..1
(-6700 3700);
FORCEPROP 2 LASTPIN (-6650 3700) SIG_NAME VR_PVCCIN_CPU0_PWM1
J 0
(-6635 3710);
DISPLAY 0.617021 (-6635 3710);
PAINT ORANGE (-6635 3710);
FORCEPROP 2 LAST $XR0 201 
J 0
(-6952 3700);
DISPLAY 0.638298 (-6952 3700);
PAINT MONO (-6952 3700);
FORCEPROP 1 LAST COMMENT_BODY TRUE
J 0
(-6575 3600);
DISPLAY 1.680851 (-6575 3600);
PAINT GREEN (-6575 3600);
DISPLAY INVISIBLE (-6575 3600);
FORCEPROP 1 LAST OFFPAGE TRUE
J 0
(-6375 3575);
DISPLAY 1.680851 (-6375 3575);
PAINT GREEN (-6375 3575);
DISPLAY INVISIBLE (-6375 3575);
FORCEPROP 2 LAST CDS_LIB mstr_standard
J 0
(-6700 3700);
DISPLAY 1.936170 (-6700 3700);
PAINT ORANGE (-6700 3700);
DISPLAY INVISIBLE (-6700 3700);
FORCEPROP 2 LAST BOM_COST PROC_VRD_VCCIN_CPU0
J 0
(-6950 3750);
DISPLAY 1.446809 (-6950 3750);
PAINT MONO (-6950 3750);
DISPLAY INVISIBLE (-6950 3750);
FORCEPROP 2 LAST ROOM PVCCIN_CPU0_PWR_VR
J 0
(-7100 3775);
DISPLAY 1.936170 (-7100 3775);
PAINT ORANGE (-7100 3775);
DISPLAY INVISIBLE (-7100 3775);
FORCEPROP 2 LAST PATH I40
J 0
(-6970 3750);
DISPLAY 1.021277 (-6970 3750);
PAINT ORANGE (-6970 3750);
DISPLAY INVISIBLE (-6970 3750);
FORCEADD VCC_CORE..1
(-7200 4525);
FORCEPROP 3 LASTPIN (-7200 4475) SIG_NAME VR_FET_SW_P12V_STBY_PVCCIN_CPU0\g
J 0
(-7190 4485);
DISPLAY 0.659574 (-7190 4485);
PAINT MONO (-7190 4485);
DISPLAY INVISIBLE (-7190 4485);
FORCEPROP 1 LAST HDL_POWER VR_FET_SW_P12V_STBY_PVCCIN_CPU0
J 1
(-7150 4575);
DISPLAY 0.617021 (-7150 4575);
PAINT GREEN (-7150 4575);
FORCEPROP 1 LAST PATH I41
J 0
(-7150 4550);
DISPLAY 0.872340 (-7150 4550);
PAINT AQUA (-7150 4550);
DISPLAY INVISIBLE (-7150 4550);
FORCEPROP 2 LAST CDS_LIB mstr_symbols
J 0
(-7200 4525);
DISPLAY 1.936170 (-7200 4525);
PAINT ORANGE (-7200 4525);
DISPLAY INVISIBLE (-7200 4525);
FORCEADD CAP..1
(-7200 4075);
FORCEPROP 1 LAST LOCATION C6R13
J 0
(-7150 4175);
DISPLAY 0.617021 (-7150 4175);
PAINT AQUA (-7150 4175);
FORCEPROP 1 LASTPIN (-7200 4175) $PN 1
J 0
(-7190 4155);
DISPLAY 0.617021 (-7190 4155);
PAINT ORANGE (-7190 4155);
FORCEPROP 1 LAST VOLTAGE 16V
J 0
(-7150 4075);
DISPLAY 0.617021 (-7150 4075);
PAINT SKYBLUE (-7150 4075);
FORCEPROP 1 LAST TOLERANCE 10%
J 0
(-7150 4025);
DISPLAY 0.617021 (-7150 4025);
PAINT SKYBLUE (-7150 4025);
FORCEPROP 1 LAST PACK_TYPE 0805
J 0
(-7150 3875);
DISPLAY 0.617021 (-7150 3875);
PAINT SKYBLUE (-7150 3875);
FORCEPROP 1 LAST MATERIAL X6S
J 0
(-7150 3975);
DISPLAY 0.617021 (-7150 3975);
PAINT SKYBLUE (-7150 3975);
FORCEPROP 1 LASTPIN (-7200 3975) $PN 2
J 0
(-7190 3955);
DISPLAY 0.617021 (-7190 3955);
PAINT ORANGE (-7190 3955);
FORCEPROP 1 LAST PART_NUMBER C95333-007
J 0
(-7150 3925);
DISPLAY 0.617021 (-7150 3925);
PAINT BLUE (-7150 3925);
FORCEPROP 1 LAST VALUE 10UF
J 0
(-7150 4125);
DISPLAY 0.617021 (-7150 4125);
PAINT SKYBLUE (-7150 4125);
FORCEPROP 2 LAST SEC_TYPE 0805
J 0
(-7150 4275);
DISPLAY 1.021277 (-7150 4275);
PAINT ORANGE (-7150 4275);
DISPLAY INVISIBLE (-7150 4275);
FORCEPROP 2 LAST SEC 1
J 0
(-7150 4275);
DISPLAY 0.680851 (-7150 4275);
PAINT MONO (-7150 4275);
DISPLAY INVISIBLE (-7150 4275);
FORCEPROP 2 LAST CDS_LOCATION C6R13
J 0
(-7150 4175);
DISPLAY 0.617021 (-7150 4175);
PAINT AQUA (-7150 4175);
DISPLAY INVISIBLE (-7150 4175);
FORCEPROP 1 LAST PATH I42
J 0
(-7150 4225);
DISPLAY 0.978723 (-7150 4225);
PAINT WHITE (-7150 4225);
DISPLAY INVISIBLE (-7150 4225);
FORCEPROP 2 LAST ROOM PVCCIN_CPU0_PWR_VR
J 0
(-7150 4225);
DISPLAY 1.361702 (-7150 4225);
PAINT ORANGE (-7150 4225);
DISPLAY INVISIBLE (-7150 4225);
FORCEPROP 2 LAST CDS_LIB mstr_discrete
J 0
(-7200 4075);
PAINT ORANGE (-7200 4075);
DISPLAY INVISIBLE (-7200 4075);
FORCEADD GND..1
(-7200 3525);
FORCEPROP 3 LASTPIN (-7200 3575) SIG_NAME GND\g
J 0
(-7190 3585);
DISPLAY 0.659574 (-7190 3585);
PAINT MONO (-7190 3585);
DISPLAY INVISIBLE (-7190 3585);
FORCEPROP 1 LAST SIZE 1B
J 0
(-7125 3475);
DISPLAY 1.723404 (-7125 3475);
PAINT GREEN (-7125 3475);
DISPLAY INVISIBLE (-7125 3475);
FORCEPROP 1 LAST PATH I43
J 0
(-7125 3525);
DISPLAY 0.872340 (-7125 3525);
PAINT AQUA (-7125 3525);
DISPLAY INVISIBLE (-7125 3525);
FORCEPROP 1 LAST HDL_POWER GND
J 0
(-7200 3675);
DISPLAY 1.723404 (-7200 3675);
PAINT GREEN (-7200 3675);
DISPLAY INVISIBLE (-7200 3675);
FORCEPROP 2 LAST BOM_COST PROC_VRD_VCCIN_CPU0
J 0
(-7575 3600);
DISPLAY 1.446809 (-7575 3600);
PAINT MONO (-7575 3600);
DISPLAY INVISIBLE (-7575 3600);
FORCEPROP 2 LAST CDS_LIB mstr_symbols
J 0
(-7200 3525);
DISPLAY 1.936170 (-7200 3525);
PAINT ORANGE (-7200 3525);
DISPLAY INVISIBLE (-7200 3525);
FORCEPROP 1 LAST VOLTAGE 0
J 0
(-7200 3525);
PAINT SKYBLUE (-7200 3525);
DISPLAY INVISIBLE (-7200 3525);
FORCEPROP 1 LAST BODY_TYPE PLUMBING
J 0
(-7245 3482);
DISPLAY 0.340426 (-7245 3482);
PAINT GREEN (-7245 3482);
DISPLAY INVISIBLE (-7245 3482);
FORCEPROP 2 LAST ROOM PVCCIN_CPU0_PWR_VR
J 0
(-7750 3600);
DISPLAY 1.936170 (-7750 3600);
PAINT ORANGE (-7750 3600);
DISPLAY INVISIBLE (-7750 3600);
FORCEADD VCC_CORE..1
(-7225 1900);
FORCEPROP 3 LASTPIN (-7225 1850) SIG_NAME VR_FET_SW_P12V_STBY_PVCCIN_CPU0\g
J 0
(-7215 1860);
DISPLAY 0.659574 (-7215 1860);
PAINT MONO (-7215 1860);
DISPLAY INVISIBLE (-7215 1860);
FORCEPROP 1 LAST HDL_POWER VR_FET_SW_P12V_STBY_PVCCIN_CPU0
J 1
(-7175 1950);
DISPLAY 0.617021 (-7175 1950);
PAINT GREEN (-7175 1950);
FORCEPROP 2 LAST CDS_LIB mstr_symbols
J 0
(-7225 1900);
PAINT ORANGE (-7225 1900);
DISPLAY INVISIBLE (-7225 1900);
FORCEPROP 1 LAST PATH I44
J 0
(-7175 1925);
DISPLAY 0.872340 (-7175 1925);
PAINT AQUA (-7175 1925);
DISPLAY INVISIBLE (-7175 1925);
FORCEADD CAP..1
(-5950 1425);
FORCEPROP 1 LAST PACK_TYPE 0402
J 0
(-5900 1225);
DISPLAY 0.617021 (-5900 1225);
PAINT SKYBLUE (-5900 1225);
FORCEPROP 1 LAST PART_NUMBER D97712-011
J 0
(-5900 1275);
DISPLAY 0.617021 (-5900 1275);
PAINT BLUE (-5900 1275);
FORCEPROP 1 LAST LOCATION C4E26
J 0
(-5900 1525);
DISPLAY 0.617021 (-5900 1525);
PAINT AQUA (-5900 1525);
FORCEPROP 1 LAST MATERIAL X6S
J 0
(-5900 1325);
DISPLAY 0.617021 (-5900 1325);
PAINT SKYBLUE (-5900 1325);
FORCEPROP 1 LAST VOLTAGE 16V
J 0
(-5900 1425);
DISPLAY 0.617021 (-5900 1425);
PAINT SKYBLUE (-5900 1425);
FORCEPROP 1 LAST TOLERANCE 10%
J 0
(-5900 1375);
DISPLAY 0.617021 (-5900 1375);
PAINT SKYBLUE (-5900 1375);
FORCEPROP 1 LAST VALUE 1.0UF
J 0
(-5900 1475);
DISPLAY 0.617021 (-5900 1475);
PAINT SKYBLUE (-5900 1475);
FORCEPROP 1 LASTPIN (-5950 1325) $PN 2
J 0
(-5940 1305);
DISPLAY 0.617021 (-5940 1305);
PAINT ORANGE (-5940 1305);
FORCEPROP 1 LASTPIN (-5950 1525) $PN 1
J 0
(-5940 1505);
DISPLAY 0.617021 (-5940 1505);
PAINT ORANGE (-5940 1505);
FORCEPROP 2 LAST ROOM PVCCIN_CPU0_PWR_VR
J 0
(-5900 1575);
DISPLAY 1.361702 (-5900 1575);
PAINT ORANGE (-5900 1575);
DISPLAY INVISIBLE (-5900 1575);
FORCEPROP 1 LAST PATH I45
J 0
(-5900 1575);
DISPLAY 0.978723 (-5900 1575);
PAINT WHITE (-5900 1575);
DISPLAY INVISIBLE (-5900 1575);
FORCEPROP 2 LAST SEC 1
J 0
(-5900 1625);
DISPLAY 0.680851 (-5900 1625);
PAINT MONO (-5900 1625);
DISPLAY INVISIBLE (-5900 1625);
FORCEPROP 2 LAST SEC_TYPE 0402
J 0
(-5900 1625);
DISPLAY 1.021277 (-5900 1625);
PAINT ORANGE (-5900 1625);
DISPLAY INVISIBLE (-5900 1625);
FORCEPROP 2 LAST CDS_LIB mstr_discrete
J 0
(-5950 1425);
PAINT ORANGE (-5950 1425);
DISPLAY INVISIBLE (-5950 1425);
FORCEADD CAP_A..1
(-6225 1475);
FORCEPROP 1 LAST LOCATION C4D49
J 0
(-6175 1575);
DISPLAY 0.617021 (-6175 1575);
PAINT AQUA (-6175 1575);
FORCEPROP 1 LAST PART_NUMBER A36096-030
J 0
(-6175 1325);
DISPLAY 0.617021 (-6175 1325);
PAINT BLUE (-6175 1325);
FORCEPROP 1 LAST VALUE 0.1UF
J 0
(-6175 1525);
DISPLAY 0.617021 (-6175 1525);
PAINT SKYBLUE (-6175 1525);
FORCEPROP 1 LAST TOLERANCE 10%
J 0
(-6175 1425);
DISPLAY 0.617021 (-6175 1425);
PAINT SKYBLUE (-6175 1425);
FORCEPROP 1 LAST PACK_TYPE 0402V
J 0
(-6175 1275);
DISPLAY 0.617021 (-6175 1275);
PAINT SKYBLUE (-6175 1275);
FORCEPROP 1 LAST VOLTAGE 16V
J 0
(-6175 1475);
DISPLAY 0.617021 (-6175 1475);
PAINT SKYBLUE (-6175 1475);
FORCEPROP 1 LAST MATERIAL X7R
J 0
(-6175 1375);
DISPLAY 0.617021 (-6175 1375);
PAINT SKYBLUE (-6175 1375);
FORCEPROP 1 LASTPIN (-6225 1575) $PN 1
J 0
(-6215 1555);
DISPLAY 0.617021 (-6215 1555);
PAINT ORANGE (-6215 1555);
FORCEPROP 1 LASTPIN (-6225 1375) $PN 2
J 0
(-6215 1355);
DISPLAY 0.617021 (-6215 1355);
PAINT ORANGE (-6215 1355);
FORCEPROP 2 LAST SEC 1
J 0
(-6175 1675);
DISPLAY 0.680851 (-6175 1675);
PAINT MONO (-6175 1675);
DISPLAY INVISIBLE (-6175 1675);
FORCEPROP 2 LAST SEC_TYPE 0402V
J 0
(-6175 1675);
DISPLAY 1.021277 (-6175 1675);
PAINT ORANGE (-6175 1675);
DISPLAY INVISIBLE (-6175 1675);
FORCEPROP 2 LAST CDS_SEC 1
J 0
(-6175 1625);
PAINT ORANGE (-6175 1625);
DISPLAY INVISIBLE (-6175 1625);
FORCEPROP 2 LAST ROOM PVCCIN_CPU0_PWR_VR
J 0
(-6175 1625);
DISPLAY 1.361702 (-6175 1625);
PAINT ORANGE (-6175 1625);
DISPLAY INVISIBLE (-6175 1625);
FORCEPROP 1 LAST PATH I46
J 0
(-6175 1625);
DISPLAY 0.978723 (-6175 1625);
PAINT WHITE (-6175 1625);
DISPLAY INVISIBLE (-6175 1625);
FORCEPROP 2 LAST CDS_LIB dev_discrete
J 0
(-6225 1475);
PAINT ORANGE (-6225 1475);
DISPLAY INVISIBLE (-6225 1475);
FORCEADD CAP..1
(-6450 1425);
FORCEPROP 1 LAST PART_NUMBER D97712-011
J 0
(-6400 1275);
DISPLAY 0.617021 (-6400 1275);
PAINT BLUE (-6400 1275);
FORCEPROP 1 LAST LOCATION C4D48
J 0
(-6400 1525);
DISPLAY 0.617021 (-6400 1525);
PAINT AQUA (-6400 1525);
FORCEPROP 1 LAST TOLERANCE 10%
J 0
(-6400 1375);
DISPLAY 0.617021 (-6400 1375);
PAINT SKYBLUE (-6400 1375);
FORCEPROP 1 LAST VALUE 1.0UF
J 0
(-6400 1475);
DISPLAY 0.617021 (-6400 1475);
PAINT SKYBLUE (-6400 1475);
FORCEPROP 1 LAST PACK_TYPE 0402
J 0
(-6400 1225);
DISPLAY 0.617021 (-6400 1225);
PAINT SKYBLUE (-6400 1225);
FORCEPROP 1 LAST VOLTAGE 16V
J 0
(-6400 1425);
DISPLAY 0.617021 (-6400 1425);
PAINT SKYBLUE (-6400 1425);
FORCEPROP 1 LAST MATERIAL X6S
J 0
(-6400 1325);
DISPLAY 0.617021 (-6400 1325);
PAINT SKYBLUE (-6400 1325);
FORCEPROP 1 LASTPIN (-6450 1325) $PN 2
J 0
(-6440 1305);
DISPLAY 0.617021 (-6440 1305);
PAINT ORANGE (-6440 1305);
FORCEPROP 1 LASTPIN (-6450 1525) $PN 1
J 0
(-6440 1505);
DISPLAY 0.617021 (-6440 1505);
PAINT ORANGE (-6440 1505);
FORCEPROP 2 LAST ROOM PVCCIN_CPU0_PWR_VR
J 0
(-6400 1575);
DISPLAY 1.361702 (-6400 1575);
PAINT ORANGE (-6400 1575);
DISPLAY INVISIBLE (-6400 1575);
FORCEPROP 1 LAST PATH I47
J 0
(-6400 1575);
DISPLAY 0.978723 (-6400 1575);
PAINT WHITE (-6400 1575);
DISPLAY INVISIBLE (-6400 1575);
FORCEPROP 2 LAST SEC 1
J 0
(-6400 1625);
DISPLAY 0.680851 (-6400 1625);
PAINT MONO (-6400 1625);
DISPLAY INVISIBLE (-6400 1625);
FORCEPROP 2 LAST SEC_TYPE 0402
J 0
(-6400 1625);
DISPLAY 1.021277 (-6400 1625);
PAINT ORANGE (-6400 1625);
DISPLAY INVISIBLE (-6400 1625);
FORCEPROP 2 LAST CDS_LIB mstr_discrete
J 0
(-6450 1425);
PAINT ORANGE (-6450 1425);
DISPLAY INVISIBLE (-6450 1425);
FORCEADD CAP..1
(-6725 1425);
FORCEPROP 1 LAST LOCATION C6R4
J 0
(-6675 1525);
DISPLAY 0.617021 (-6675 1525);
PAINT AQUA (-6675 1525);
FORCEPROP 1 LAST PART_NUMBER C95333-007
J 0
(-6675 1275);
DISPLAY 0.617021 (-6675 1275);
PAINT BLUE (-6675 1275);
FORCEPROP 1 LAST VALUE 10UF
J 0
(-6675 1475);
DISPLAY 0.617021 (-6675 1475);
PAINT SKYBLUE (-6675 1475);
FORCEPROP 1 LAST TOLERANCE 10%
J 0
(-6675 1375);
DISPLAY 0.617021 (-6675 1375);
PAINT SKYBLUE (-6675 1375);
FORCEPROP 1 LAST PACK_TYPE 0805
J 0
(-6675 1225);
DISPLAY 0.617021 (-6675 1225);
PAINT SKYBLUE (-6675 1225);
FORCEPROP 1 LAST VOLTAGE 16V
J 0
(-6675 1425);
DISPLAY 0.617021 (-6675 1425);
PAINT SKYBLUE (-6675 1425);
FORCEPROP 1 LAST MATERIAL X6S
J 0
(-6675 1325);
DISPLAY 0.617021 (-6675 1325);
PAINT SKYBLUE (-6675 1325);
FORCEPROP 1 LASTPIN (-6725 1325) $PN 2
J 0
(-6715 1305);
DISPLAY 0.617021 (-6715 1305);
PAINT ORANGE (-6715 1305);
FORCEPROP 1 LASTPIN (-6725 1525) $PN 1
J 0
(-6715 1505);
DISPLAY 0.617021 (-6715 1505);
PAINT ORANGE (-6715 1505);
FORCEPROP 2 LAST ROOM PVCCIN_CPU0_PWR_VR
J 0
(-6675 1575);
DISPLAY 1.361702 (-6675 1575);
PAINT ORANGE (-6675 1575);
DISPLAY INVISIBLE (-6675 1575);
FORCEPROP 1 LAST PATH I48
J 0
(-6675 1575);
DISPLAY 0.978723 (-6675 1575);
PAINT WHITE (-6675 1575);
DISPLAY INVISIBLE (-6675 1575);
FORCEPROP 2 LAST SEC 1
J 0
(-6675 1625);
DISPLAY 0.680851 (-6675 1625);
PAINT MONO (-6675 1625);
DISPLAY INVISIBLE (-6675 1625);
FORCEPROP 2 LAST SEC_TYPE 0805
J 0
(-6675 1625);
DISPLAY 1.021277 (-6675 1625);
PAINT ORANGE (-6675 1625);
DISPLAY INVISIBLE (-6675 1625);
FORCEPROP 2 LAST CDS_LOCATION C6R4
J 0
(-6675 1525);
DISPLAY 0.617021 (-6675 1525);
PAINT AQUA (-6675 1525);
DISPLAY INVISIBLE (-6675 1525);
FORCEPROP 2 LAST CDS_LIB mstr_discrete
J 0
(-6725 1425);
PAINT ORANGE (-6725 1425);
DISPLAY INVISIBLE (-6725 1425);
FORCEADD CAP..1
(-6975 1450);
FORCEPROP 1 LAST LOCATION C6P22
J 0
(-6925 1550);
DISPLAY 0.617021 (-6925 1550);
PAINT AQUA (-6925 1550);
FORCEPROP 1 LAST PART_NUMBER C95333-007
J 0
(-6925 1300);
DISPLAY 0.617021 (-6925 1300);
PAINT BLUE (-6925 1300);
FORCEPROP 1 LASTPIN (-6975 1550) $PN 1
J 0
(-6965 1530);
DISPLAY 0.617021 (-6965 1530);
PAINT ORANGE (-6965 1530);
FORCEPROP 1 LAST VALUE 10UF
J 0
(-6925 1500);
DISPLAY 0.617021 (-6925 1500);
PAINT SKYBLUE (-6925 1500);
FORCEPROP 1 LAST TOLERANCE 10%
J 0
(-6925 1400);
DISPLAY 0.617021 (-6925 1400);
PAINT SKYBLUE (-6925 1400);
FORCEPROP 1 LAST PACK_TYPE 0805
J 0
(-6925 1250);
DISPLAY 0.617021 (-6925 1250);
PAINT SKYBLUE (-6925 1250);
FORCEPROP 1 LAST VOLTAGE 16V
J 0
(-6925 1450);
DISPLAY 0.617021 (-6925 1450);
PAINT SKYBLUE (-6925 1450);
FORCEPROP 1 LAST MATERIAL X6S
J 0
(-6925 1350);
DISPLAY 0.617021 (-6925 1350);
PAINT SKYBLUE (-6925 1350);
FORCEPROP 1 LASTPIN (-6975 1350) $PN 2
J 0
(-6965 1330);
DISPLAY 0.617021 (-6965 1330);
PAINT ORANGE (-6965 1330);
FORCEPROP 2 LAST ROOM PVCCIN_CPU0_PWR_VR
J 0
(-6925 1600);
DISPLAY 1.361702 (-6925 1600);
PAINT ORANGE (-6925 1600);
DISPLAY INVISIBLE (-6925 1600);
FORCEPROP 1 LAST PATH I49
J 0
(-6925 1600);
DISPLAY 0.978723 (-6925 1600);
PAINT WHITE (-6925 1600);
DISPLAY INVISIBLE (-6925 1600);
FORCEPROP 2 LAST CDS_LOCATION C6P22
J 0
(-6925 1550);
DISPLAY 0.617021 (-6925 1550);
PAINT AQUA (-6925 1550);
DISPLAY INVISIBLE (-6925 1550);
FORCEPROP 2 LAST SEC 1
J 0
(-6925 1650);
DISPLAY 0.680851 (-6925 1650);
PAINT MONO (-6925 1650);
DISPLAY INVISIBLE (-6925 1650);
FORCEPROP 2 LAST SEC_TYPE 0805
J 0
(-6925 1650);
DISPLAY 1.021277 (-6925 1650);
PAINT ORANGE (-6925 1650);
DISPLAY INVISIBLE (-6925 1650);
FORCEPROP 2 LAST CDS_LIB mstr_discrete
J 0
(-6975 1450);
PAINT ORANGE (-6975 1450);
DISPLAY INVISIBLE (-6975 1450);
FORCEADD INDUCTOR..1
(-1775 3500);
FORCEPROP 1 LAST VALUE 0.12UH
J 2
(-1780 3390);
DISPLAY 0.617021 (-1780 3390);
PAINT SKYBLUE (-1780 3390);
FORCEPROP 1 LAST PART_NUMBER D92183-034
J 0
(-1900 3450);
DISPLAY 0.617021 (-1900 3450);
PAINT BLUE (-1900 3450);
FORCEPROP 1 LAST LOCATION L4E1
J 0
(-1875 3550);
DISPLAY 0.617021 (-1875 3550);
PAINT AQUA (-1875 3550);
FORCEPROP 1 LAST MATERIAL IND
J 0
(-1735 3390);
DISPLAY 0.617021 (-1735 3390);
PAINT SKYBLUE (-1735 3390);
FORCEPROP 1 LAST PACK_TYPE SM
J 0
(-1610 3390);
DISPLAY 0.617021 (-1610 3390);
PAINT SKYBLUE (-1610 3390);
FORCEPROP 1 LASTPIN (-1675 3500) $PN 2
J 2
(-1665 3510);
DISPLAY 0.617021 (-1665 3510);
PAINT WHITE (-1665 3510);
FORCEPROP 1 LASTPIN (-1875 3500) $PN 1
J 0
(-1875 3510);
DISPLAY 0.617021 (-1875 3510);
PAINT WHITE (-1875 3510);
FORCEPROP 2 LAST CDS_SEC 1
J 0
(-1875 3700);
PAINT MONO (-1875 3700);
DISPLAY INVISIBLE (-1875 3700);
FORCEPROP 2 LAST $SEC 1
J 0
(-1875 3700);
PAINT MONO (-1875 3700);
DISPLAY INVISIBLE (-1875 3700);
FORCEPROP 1 LAST PATH I5
J 0
(-1875 3650);
DISPLAY 0.978723 (-1875 3650);
PAINT ORANGE (-1875 3650);
DISPLAY INVISIBLE (-1875 3650);
FORCEPROP 2 LAST ROOM PVCCIN_CPU0_PWR_VR
J 0
(-1875 3600);
DISPLAY 1.361702 (-1875 3600);
PAINT ORANGE (-1875 3600);
DISPLAY INVISIBLE (-1875 3600);
FORCEPROP 2 LAST CDS_LIB mstr_discrete
J 0
(-1775 3500);
PAINT ORANGE (-1775 3500);
DISPLAY INVISIBLE (-1775 3500);
FORCEPROP 2 LAST CDS_LOCATION L4E1
J 0
(-1875 3550);
DISPLAY 0.617021 (-1875 3550);
PAINT AQUA (-1875 3550);
DISPLAY INVISIBLE (-1875 3550);
FORCEADD OFFPAGE..1
(-6725 1075);
FORCEPROP 2 LAST $XR0 201 
J 0
(-6977 1075);
DISPLAY 0.638298 (-6977 1075);
PAINT MONO (-6977 1075);
FORCEPROP 2 LAST PATH I50
J 0
(-6670 1150);
DISPLAY 1.021277 (-6670 1150);
PAINT ORANGE (-6670 1150);
DISPLAY INVISIBLE (-6670 1150);
FORCEPROP 2 LAST CDS_LIB mstr_standard
J 0
(-6725 1075);
PAINT ORANGE (-6725 1075);
DISPLAY INVISIBLE (-6725 1075);
FORCEPROP 2 LAST ROOM PVCCIN_CPU0_PWR_VR
J 0
(-7125 1150);
DISPLAY 1.936170 (-7125 1150);
PAINT ORANGE (-7125 1150);
DISPLAY INVISIBLE (-7125 1150);
FORCEPROP 2 LAST BOM_COST PROC_VRD_VCCIN_CPU0
J 0
(-6975 1125);
DISPLAY 1.446809 (-6975 1125);
PAINT MONO (-6975 1125);
DISPLAY INVISIBLE (-6975 1125);
FORCEPROP 1 LAST COMMENT_BODY TRUE
J 0
(-6600 975);
DISPLAY 1.680851 (-6600 975);
PAINT GREEN (-6600 975);
DISPLAY INVISIBLE (-6600 975);
FORCEPROP 1 LAST OFFPAGE TRUE
J 0
(-6400 950);
DISPLAY 1.680851 (-6400 950);
PAINT GREEN (-6400 950);
DISPLAY INVISIBLE (-6400 950);
FORCEADD CAP..1
(-7225 1475);
FORCEPROP 1 LAST LOCATION C6N8
J 0
(-7175 1575);
DISPLAY 0.617021 (-7175 1575);
PAINT AQUA (-7175 1575);
FORCEPROP 1 LAST PART_NUMBER C95333-007
J 0
(-7175 1325);
DISPLAY 0.617021 (-7175 1325);
PAINT BLUE (-7175 1325);
FORCEPROP 1 LAST VALUE 10UF
J 0
(-7175 1525);
DISPLAY 0.617021 (-7175 1525);
PAINT SKYBLUE (-7175 1525);
FORCEPROP 1 LAST TOLERANCE 10%
J 0
(-7175 1425);
DISPLAY 0.617021 (-7175 1425);
PAINT SKYBLUE (-7175 1425);
FORCEPROP 1 LAST PACK_TYPE 0805
J 0
(-7175 1275);
DISPLAY 0.617021 (-7175 1275);
PAINT SKYBLUE (-7175 1275);
FORCEPROP 1 LAST VOLTAGE 16V
J 0
(-7175 1475);
DISPLAY 0.617021 (-7175 1475);
PAINT SKYBLUE (-7175 1475);
FORCEPROP 1 LAST MATERIAL X6S
J 0
(-7175 1375);
DISPLAY 0.617021 (-7175 1375);
PAINT SKYBLUE (-7175 1375);
FORCEPROP 1 LASTPIN (-7225 1575) $PN 1
J 0
(-7215 1555);
DISPLAY 0.617021 (-7215 1555);
PAINT ORANGE (-7215 1555);
FORCEPROP 1 LASTPIN (-7225 1375) $PN 2
J 0
(-7215 1355);
DISPLAY 0.617021 (-7215 1355);
PAINT ORANGE (-7215 1355);
FORCEPROP 2 LAST SEC_TYPE 0805
J 0
(-7175 1675);
DISPLAY 1.021277 (-7175 1675);
PAINT ORANGE (-7175 1675);
DISPLAY INVISIBLE (-7175 1675);
FORCEPROP 2 LAST SEC 1
J 0
(-7175 1675);
DISPLAY 0.680851 (-7175 1675);
PAINT MONO (-7175 1675);
DISPLAY INVISIBLE (-7175 1675);
FORCEPROP 1 LAST PATH I51
J 0
(-7175 1625);
DISPLAY 0.978723 (-7175 1625);
PAINT WHITE (-7175 1625);
DISPLAY INVISIBLE (-7175 1625);
FORCEPROP 2 LAST ROOM PVCCIN_CPU0_PWR_VR
J 0
(-7175 1625);
DISPLAY 1.361702 (-7175 1625);
PAINT ORANGE (-7175 1625);
DISPLAY INVISIBLE (-7175 1625);
FORCEPROP 2 LAST CDS_LOCATION C6N8
J 0
(-7175 1575);
DISPLAY 0.617021 (-7175 1575);
PAINT AQUA (-7175 1575);
DISPLAY INVISIBLE (-7175 1575);
FORCEPROP 2 LAST CDS_LIB mstr_discrete
J 0
(-7225 1475);
PAINT ORANGE (-7225 1475);
DISPLAY INVISIBLE (-7225 1475);
FORCEADD GND..1
(-7225 1050);
FORCEPROP 3 LASTPIN (-7225 1100) SIG_NAME GND\g
J 0
(-7215 1110);
DISPLAY 0.659574 (-7215 1110);
PAINT MONO (-7215 1110);
DISPLAY INVISIBLE (-7215 1110);
FORCEPROP 1 LAST PATH I52
J 0
(-7150 1050);
DISPLAY 0.872340 (-7150 1050);
PAINT AQUA (-7150 1050);
DISPLAY INVISIBLE (-7150 1050);
FORCEPROP 1 LAST SIZE 1B
J 0
(-7150 1000);
DISPLAY 1.723404 (-7150 1000);
PAINT GREEN (-7150 1000);
DISPLAY INVISIBLE (-7150 1000);
FORCEPROP 1 LAST HDL_POWER GND
J 0
(-7225 1200);
DISPLAY 1.723404 (-7225 1200);
PAINT GREEN (-7225 1200);
DISPLAY INVISIBLE (-7225 1200);
FORCEPROP 1 LAST VOLTAGE 0
J 0
(-7225 1050);
PAINT SKYBLUE (-7225 1050);
DISPLAY INVISIBLE (-7225 1050);
FORCEPROP 2 LAST CDS_LIB mstr_symbols
J 0
(-7225 1050);
PAINT ORANGE (-7225 1050);
DISPLAY INVISIBLE (-7225 1050);
FORCEPROP 2 LAST BOM_COST PROC_VRD_VCCIN_CPU0
J 0
(-7600 1125);
DISPLAY 1.446809 (-7600 1125);
PAINT MONO (-7600 1125);
DISPLAY INVISIBLE (-7600 1125);
FORCEPROP 2 LAST ROOM PVCCIN_CPU0_PWR_VR
J 0
(-7775 1125);
DISPLAY 1.936170 (-7775 1125);
PAINT ORANGE (-7775 1125);
DISPLAY INVISIBLE (-7775 1125);
FORCEPROP 1 LAST BODY_TYPE PLUMBING
J 0
(-7270 1007);
DISPLAY 0.340426 (-7270 1007);
PAINT GREEN (-7270 1007);
DISPLAY INVISIBLE (-7270 1007);
FORCEADD P5V_STBY..1
(-4700 2100);
FORCEPROP 3 LASTPIN (-4700 2050) SIG_NAME P5V_STBY\g
J 0
(-4690 2060);
DISPLAY 0.659574 (-4690 2060);
PAINT MONO (-4690 2060);
DISPLAY INVISIBLE (-4690 2060);
FORCEPROP 1 LAST VOLTAGE 5.0V
J 0
(-4745 2057);
DISPLAY 0.340426 (-4745 2057);
PAINT SKYBLUE (-4745 2057);
DISPLAY INVISIBLE (-4745 2057);
FORCEPROP 2 LAST CDS_LIB mstr_symbols
J 0
(-4700 2100);
PAINT ORANGE (-4700 2100);
DISPLAY INVISIBLE (-4700 2100);
FORCEPROP 1 LAST SIZE 1B
J 0
(-4655 2122);
DISPLAY 0.340426 (-4655 2122);
PAINT GREEN (-4655 2122);
DISPLAY INVISIBLE (-4655 2122);
FORCEPROP 1 LAST BODY_TYPE PLUMBING
J 0
(-4745 2057);
DISPLAY 0.340426 (-4745 2057);
PAINT GREEN (-4745 2057);
DISPLAY INVISIBLE (-4745 2057);
FORCEPROP 1 LAST PATH I59
J 0
(-4655 2102);
DISPLAY 0.340426 (-4655 2102);
PAINT GREEN (-4655 2102);
DISPLAY INVISIBLE (-4655 2102);
FORCEPROP 1 LAST HDL_POWER P5V_STBY
J 0
(-5000 1975);
DISPLAY 0.872340 (-5000 1975);
PAINT ORANGE (-5000 1975);
DISPLAY INVISIBLE (-5000 1975);
FORCEADD P5V_STBY..1
(-4675 4750);
FORCEPROP 3 LASTPIN (-4675 4700) SIG_NAME P5V_STBY\g
J 0
(-4665 4710);
DISPLAY 0.659574 (-4665 4710);
PAINT MONO (-4665 4710);
DISPLAY INVISIBLE (-4665 4710);
FORCEPROP 1 LAST PATH I60
J 0
(-4630 4752);
DISPLAY 0.340426 (-4630 4752);
PAINT GREEN (-4630 4752);
DISPLAY INVISIBLE (-4630 4752);
FORCEPROP 1 LAST SIZE 1B
J 0
(-4630 4772);
DISPLAY 0.340426 (-4630 4772);
PAINT GREEN (-4630 4772);
DISPLAY INVISIBLE (-4630 4772);
FORCEPROP 2 LAST CDS_LIB mstr_symbols
J 0
(-4675 4750);
PAINT ORANGE (-4675 4750);
DISPLAY INVISIBLE (-4675 4750);
FORCEPROP 1 LAST VOLTAGE 5.0V
J 0
(-4720 4707);
DISPLAY 0.340426 (-4720 4707);
PAINT SKYBLUE (-4720 4707);
DISPLAY INVISIBLE (-4720 4707);
FORCEPROP 1 LAST BODY_TYPE PLUMBING
J 0
(-4720 4707);
DISPLAY 0.340426 (-4720 4707);
PAINT GREEN (-4720 4707);
DISPLAY INVISIBLE (-4720 4707);
FORCEPROP 1 LAST HDL_POWER P5V_STBY
J 0
(-4975 4625);
DISPLAY 0.872340 (-4975 4625);
PAINT ORANGE (-4975 4625);
DISPLAY INVISIBLE (-4975 4625);
FORCEADD CAP_A..1
(-875 3300);
FORCEPROP 1 LAST MATERIAL X6S
J 0
(-825 3200);
DISPLAY 0.617021 (-825 3200);
PAINT SKYBLUE (-825 3200);
FORCEPROP 1 LAST TOLERANCE 20%
J 0
(-825 3250);
DISPLAY 0.617021 (-825 3250);
PAINT SKYBLUE (-825 3250);
FORCEPROP 1 LAST PACK_TYPE 0603V
J 0
(-825 3100);
DISPLAY 0.617021 (-825 3100);
PAINT SKYBLUE (-825 3100);
FORCEPROP 1 LAST VALUE 22.0UF
J 0
(-825 3350);
DISPLAY 0.617021 (-825 3350);
PAINT SKYBLUE (-825 3350);
FORCEPROP 1 LAST PART_NUMBER E15431-004
J 0
(-825 3150);
DISPLAY 0.617021 (-825 3150);
PAINT BLUE (-825 3150);
FORCEPROP 1 LAST LOCATION C4E3
J 0
(-825 3400);
DISPLAY 0.617021 (-825 3400);
PAINT AQUA (-825 3400);
FORCEPROP 1 LAST VOLTAGE 4V
J 0
(-825 3300);
DISPLAY 0.617021 (-825 3300);
PAINT SKYBLUE (-825 3300);
FORCEPROP 1 LASTPIN (-875 3400) $PN 1
J 0
(-865 3380);
DISPLAY 0.617021 (-865 3380);
PAINT ORANGE (-865 3380);
FORCEPROP 1 LASTPIN (-875 3200) $PN 2
J 0
(-865 3180);
DISPLAY 0.617021 (-865 3180);
PAINT ORANGE (-865 3180);
FORCEPROP 1 LAST PATH I61
J 0
(-825 3450);
DISPLAY 0.978723 (-825 3450);
PAINT WHITE (-825 3450);
DISPLAY INVISIBLE (-825 3450);
FORCEPROP 2 LAST CDS_SEC 1
J 0
(-825 3450);
PAINT ORANGE (-825 3450);
DISPLAY INVISIBLE (-825 3450);
FORCEPROP 2 LAST CDS_LOCATION C4E3
J 0
(-825 3400);
DISPLAY 0.617021 (-825 3400);
PAINT AQUA (-825 3400);
DISPLAY INVISIBLE (-825 3400);
FORCEPROP 2 LAST SEC 1
J 0
(-825 3500);
DISPLAY 0.680851 (-825 3500);
PAINT MONO (-825 3500);
DISPLAY INVISIBLE (-825 3500);
FORCEPROP 2 LAST SEC_TYPE 0603V
J 0
(-825 3500);
DISPLAY 1.021277 (-825 3500);
PAINT ORANGE (-825 3500);
DISPLAY INVISIBLE (-825 3500);
FORCEPROP 2 LAST CDS_LIB dev_discrete
J 0
(-875 3300);
PAINT ORANGE (-875 3300);
DISPLAY INVISIBLE (-875 3300);
FORCEADD CAP_A..1
(-575 650);
FORCEPROP 1 LAST VOLTAGE 4V
J 0
(-525 650);
DISPLAY 0.617021 (-525 650);
PAINT SKYBLUE (-525 650);
FORCEPROP 1 LAST VALUE 22.0UF
J 0
(-525 700);
DISPLAY 0.617021 (-525 700);
PAINT SKYBLUE (-525 700);
FORCEPROP 1 LASTPIN (-575 750) $PN 1
J 0
(-565 730);
DISPLAY 0.617021 (-565 730);
PAINT ORANGE (-565 730);
FORCEPROP 1 LAST PACK_TYPE 0603V
J 0
(-525 450);
DISPLAY 0.617021 (-525 450);
PAINT SKYBLUE (-525 450);
FORCEPROP 1 LASTPIN (-575 550) $PN 2
J 0
(-565 530);
DISPLAY 0.617021 (-565 530);
PAINT ORANGE (-565 530);
FORCEPROP 1 LAST MATERIAL X6S
J 0
(-525 550);
DISPLAY 0.617021 (-525 550);
PAINT SKYBLUE (-525 550);
FORCEPROP 1 LAST TOLERANCE 20%
J 0
(-525 600);
DISPLAY 0.617021 (-525 600);
PAINT SKYBLUE (-525 600);
FORCEPROP 1 LAST LOCATION C6P16
J 0
(-525 750);
DISPLAY 0.617021 (-525 750);
PAINT AQUA (-525 750);
FORCEPROP 1 LAST PART_NUMBER E15431-004
J 0
(-525 500);
DISPLAY 0.617021 (-525 500);
PAINT BLUE (-525 500);
FORCEPROP 2 LAST CDS_LIB dev_discrete
J 0
(-575 650);
PAINT ORANGE (-575 650);
DISPLAY INVISIBLE (-575 650);
FORCEPROP 2 LAST SEC 1
J 0
(-525 850);
DISPLAY 0.680851 (-525 850);
PAINT MONO (-525 850);
DISPLAY INVISIBLE (-525 850);
FORCEPROP 1 LAST PATH I62
J 0
(-525 800);
DISPLAY 0.978723 (-525 800);
PAINT WHITE (-525 800);
DISPLAY INVISIBLE (-525 800);
FORCEPROP 2 LAST CDS_LOCATION C6P16
J 0
(-525 750);
DISPLAY 0.617021 (-525 750);
PAINT AQUA (-525 750);
DISPLAY INVISIBLE (-525 750);
FORCEPROP 2 LAST CDS_SEC 1
J 0
(-525 800);
PAINT ORANGE (-525 800);
DISPLAY INVISIBLE (-525 800);
FORCEPROP 2 LAST SEC_TYPE 0603V
J 0
(-525 850);
DISPLAY 1.021277 (-525 850);
PAINT ORANGE (-525 850);
DISPLAY INVISIBLE (-525 850);
FORCEADD IR354XX..1
(-3425 3800);
FORCEPROP 2 LASTPIN (-3925 3700) $PN 34
J 2
(-3935 3710);
DISPLAY 0.617021 (-3935 3710);
PAINT MONO (-3935 3710);
FORCEPROP 2 LASTPIN (-3925 3800) $PN 6
J 2
(-3935 3810);
DISPLAY 0.617021 (-3935 3810);
PAINT MONO (-3935 3810);
FORCEPROP 2 LASTPIN (-3925 4050) $PN 35
J 2
(-3935 4060);
DISPLAY 0.617021 (-3935 4060);
PAINT MONO (-3935 4060);
FORCEPROP 2 LASTPIN (-3925 3850) $PN 41
J 2
(-3935 3860);
DISPLAY 0.617021 (-3935 3860);
PAINT MONO (-3935 3860);
FORCEPROP 2 LASTPIN (-2925 3250) $PN 5
J 0
(-2915 3260);
DISPLAY 0.617021 (-2915 3260);
PAINT MONO (-2915 3260);
FORCEPROP 2 LASTPIN (-2925 3300) $PN 7
J 0
(-2915 3310);
DISPLAY 0.617021 (-2915 3310);
PAINT MONO (-2915 3310);
FORCEPROP 2 LASTPIN (-2925 3400) $PN 2
J 0
(-2915 3410);
DISPLAY 0.617021 (-2915 3410);
PAINT MONO (-2915 3410);
FORCEPROP 2 LASTPIN (-2925 3850) $PN 36
J 0
(-2915 3860);
DISPLAY 0.617021 (-2915 3860);
PAINT MONO (-2915 3860);
FORCEPROP 2 LASTPIN (-3925 4250) $PN 25
J 2
(-3935 4260);
DISPLAY 0.617021 (-3935 4260);
PAINT MONO (-3935 4260);
FORCEPROP 2 LASTPIN (-3925 4350) $PN 3
J 2
(-3935 4360);
DISPLAY 0.617021 (-3935 4360);
PAINT MONO (-3935 4360);
FORCEPROP 1 LAST MATERIAL IC
J 0
(-3875 4550);
DISPLAY 0.617021 (-3875 4550);
PAINT SKYBLUE (-3875 4550);
FORCEPROP 1 LAST LOCATION EU4E1
J 0
(-3875 4600);
DISPLAY 0.617021 (-3875 4600);
PAINT AQUA (-3875 4600);
FORCEPROP 1 LAST VALUE IR35411
J 1
(-3425 4425);
DISPLAY 0.617021 (-3425 4425);
PAINT SKYBLUE (-3425 4425);
FORCEPROP 2 LASTPIN (-2925 4350) $PN 38
J 0
(-2915 4360);
DISPLAY 0.617021 (-2915 4360);
PAINT MONO (-2915 4360);
FORCEPROP 2 LASTPIN (-2925 4100) $PN 31
J 0
(-2915 4110);
DISPLAY 0.617021 (-2915 4110);
PAINT MONO (-2915 4110);
FORCEPROP 2 LASTPIN (-2925 4150) $PN 37
J 0
(-2915 4160);
DISPLAY 0.617021 (-2915 4160);
PAINT MONO (-2915 4160);
FORCEPROP 1 LAST PART_NUMBER H73688-001
J 0
(-3875 3100);
DISPLAY 0.617021 (-3875 3100);
PAINT BLUE (-3875 3100);
FORCEPROP 2 LASTPIN (-3925 3500) $PN 33
J 2
(-3935 3510);
DISPLAY 0.617021 (-3935 3510);
PAINT MONO (-3935 3510);
FORCEPROP 2 LASTPIN (-3925 4150) $PN 4
J 2
(-3935 4160);
DISPLAY 0.617021 (-3935 4160);
PAINT MONO (-3935 4160);
FORCEPROP 2 LASTPIN (-2925 3350) $PN 40
J 0
(-2915 3360);
DISPLAY 0.617021 (-2915 3360);
PAINT MONO (-2915 3360);
FORCEPROP 2 LASTPIN (-3925 3450) $PN 32
J 2
(-3935 3460);
DISPLAY 0.617021 (-3935 3460);
PAINT MONO (-3935 3460);
FORCEPROP 2 LASTPIN (-2925 3500) $PN 10
J 0
(-2915 3510);
DISPLAY 0.617021 (-2915 3510);
PAINT MONO (-2915 3510);
FORCEPROP 2 LASTPIN (-3925 3600) $PN 39
J 2
(-3935 3610);
DISPLAY 0.617021 (-3935 3610);
PAINT MONO (-3935 3610);
FORCEPROP 2 LASTPIN (-3925 4300) $PN 30
J 2
(-3935 4310);
DISPLAY 0.617021 (-3935 4310);
PAINT MONO (-3935 4310);
FORCEPROP 2 LASTPIN (-3925 3950) $PN 1
J 2
(-3935 3960);
DISPLAY 0.617021 (-3935 3960);
PAINT MONO (-3935 3960);
FORCEPROP 2 LAST CDS_LIB mstr_discrete
J 0
(-3425 3800);
PAINT ORANGE (-3425 3800);
DISPLAY INVISIBLE (-3425 3800);
FORCEPROP 2 LAST CDS_LOCATION EU4E1
J 0
(-3875 4600);
PAINT GREEN (-3875 4600);
DISPLAY INVISIBLE (-3875 4600);
FORCEPROP 1 LAST PACK_TYPE SM
J 0
(-3875 4650);
PAINT SKYBLUE (-3875 4650);
DISPLAY INVISIBLE (-3875 4650);
FORCEPROP 2 LAST CDS_SEC 1
J 0
(-3875 4650);
PAINT MONO (-3875 4650);
DISPLAY INVISIBLE (-3875 4650);
FORCEPROP 2 LAST $SEC 1
J 0
(-3875 4650);
PAINT MONO (-3875 4650);
DISPLAY INVISIBLE (-3875 4650);
FORCEPROP 1 LAST PATH I63
J 0
(-3425 4550);
PAINT GREEN (-3425 4550);
DISPLAY INVISIBLE (-3425 4550);
FORCEADD IR354XX..1
(-3475 1175);
FORCEPROP 2 LASTPIN (-2975 1725) $PN 38
J 0
(-2965 1735);
DISPLAY 0.617021 (-2965 1735);
PAINT MONO (-2965 1735);
FORCEPROP 1 LAST VALUE IR35411
J 1
(-3475 1800);
DISPLAY 0.617021 (-3475 1800);
PAINT SKYBLUE (-3475 1800);
FORCEPROP 1 LAST LOCATION EU4D6
J 0
(-3925 1975);
DISPLAY 0.617021 (-3925 1975);
PAINT AQUA (-3925 1975);
FORCEPROP 2 LASTPIN (-3975 1625) $PN 25
J 2
(-3985 1635);
DISPLAY 0.617021 (-3985 1635);
PAINT MONO (-3985 1635);
FORCEPROP 2 LASTPIN (-2975 675) $PN 7
J 0
(-2965 685);
DISPLAY 0.617021 (-2965 685);
PAINT MONO (-2965 685);
FORCEPROP 2 LASTPIN (-2975 625) $PN 5
J 0
(-2965 635);
DISPLAY 0.617021 (-2965 635);
PAINT MONO (-2965 635);
FORCEPROP 2 LASTPIN (-2975 1525) $PN 37
J 0
(-2965 1535);
DISPLAY 0.617021 (-2965 1535);
PAINT MONO (-2965 1535);
FORCEPROP 2 LASTPIN (-2975 1475) $PN 31
J 0
(-2965 1485);
DISPLAY 0.617021 (-2965 1485);
PAINT MONO (-2965 1485);
FORCEPROP 2 LASTPIN (-2975 875) $PN 10
J 0
(-2965 885);
DISPLAY 0.617021 (-2965 885);
PAINT MONO (-2965 885);
FORCEPROP 2 LASTPIN (-2975 775) $PN 2
J 0
(-2965 785);
DISPLAY 0.617021 (-2965 785);
PAINT MONO (-2965 785);
FORCEPROP 2 LASTPIN (-3975 875) $PN 33
J 2
(-3985 885);
DISPLAY 0.617021 (-3985 885);
PAINT MONO (-3985 885);
FORCEPROP 2 LASTPIN (-3975 975) $PN 39
J 2
(-3985 985);
DISPLAY 0.617021 (-3985 985);
PAINT MONO (-3985 985);
FORCEPROP 2 LASTPIN (-3975 1075) $PN 34
J 2
(-3985 1085);
DISPLAY 0.617021 (-3985 1085);
PAINT MONO (-3985 1085);
FORCEPROP 2 LASTPIN (-3975 1225) $PN 41
J 2
(-3985 1235);
DISPLAY 0.617021 (-3985 1235);
PAINT MONO (-3985 1235);
FORCEPROP 2 LASTPIN (-3975 1175) $PN 6
J 2
(-3985 1185);
DISPLAY 0.617021 (-3985 1185);
PAINT MONO (-3985 1185);
FORCEPROP 2 LASTPIN (-3975 1325) $PN 1
J 2
(-3985 1335);
DISPLAY 0.617021 (-3985 1335);
PAINT MONO (-3985 1335);
FORCEPROP 2 LASTPIN (-3975 1425) $PN 35
J 2
(-3985 1435);
DISPLAY 0.617021 (-3985 1435);
PAINT MONO (-3985 1435);
FORCEPROP 2 LASTPIN (-3975 1525) $PN 4
J 2
(-3985 1535);
DISPLAY 0.617021 (-3985 1535);
PAINT MONO (-3985 1535);
FORCEPROP 1 LAST MATERIAL IC
J 0
(-3925 1925);
DISPLAY 0.617021 (-3925 1925);
PAINT SKYBLUE (-3925 1925);
FORCEPROP 2 LASTPIN (-3975 1675) $PN 30
J 2
(-3985 1685);
DISPLAY 0.617021 (-3985 1685);
PAINT MONO (-3985 1685);
FORCEPROP 2 LASTPIN (-3975 1725) $PN 3
J 2
(-3985 1735);
DISPLAY 0.617021 (-3985 1735);
PAINT MONO (-3985 1735);
FORCEPROP 2 LASTPIN (-2975 725) $PN 40
J 0
(-2965 735);
DISPLAY 0.617021 (-2965 735);
PAINT MONO (-2965 735);
FORCEPROP 2 LASTPIN (-2975 1225) $PN 36
J 0
(-2965 1235);
DISPLAY 0.617021 (-2965 1235);
PAINT MONO (-2965 1235);
FORCEPROP 1 LAST PART_NUMBER H73688-001
J 0
(-3850 475);
DISPLAY 0.617021 (-3850 475);
PAINT BLUE (-3850 475);
FORCEPROP 2 LASTPIN (-3975 825) $PN 32
J 2
(-3985 835);
DISPLAY 0.617021 (-3985 835);
PAINT MONO (-3985 835);
FORCEPROP 2 LAST CDS_LOCATION EU4D6
J 0
(-3925 1975);
PAINT GREEN (-3925 1975);
DISPLAY INVISIBLE (-3925 1975);
FORCEPROP 1 LAST PATH I64
J 0
(-3475 1925);
PAINT GREEN (-3475 1925);
DISPLAY INVISIBLE (-3475 1925);
FORCEPROP 2 LAST CDS_LIB mstr_discrete
J 0
(-3475 1175);
PAINT ORANGE (-3475 1175);
DISPLAY INVISIBLE (-3475 1175);
FORCEPROP 2 LAST $SEC 1
J 0
(-3925 2025);
PAINT MONO (-3925 2025);
DISPLAY INVISIBLE (-3925 2025);
FORCEPROP 2 LAST CDS_SEC 1
J 0
(-3925 2025);
PAINT MONO (-3925 2025);
DISPLAY INVISIBLE (-3925 2025);
FORCEPROP 1 LAST PACK_TYPE SM
J 0
(-3925 2025);
PAINT SKYBLUE (-3925 2025);
DISPLAY INVISIBLE (-3925 2025);
FORCEADD RES..2
(-750 3900);
FORCEPROP 1 LAST PART_NUMBER G21796-187
J 0
(-710 3775);
DISPLAY 0.617021 (-710 3775);
PAINT BLUE (-710 3775);
FORCEPROP 1 LAST LOCATION R4E22
J 0
(-705 4025);
DISPLAY 0.617021 (-705 4025);
PAINT AQUA (-705 4025);
FORCEPROP 1 LAST VALUE 68.1K
J 0
(-705 3975);
DISPLAY 0.617021 (-705 3975);
PAINT SKYBLUE (-705 3975);
FORCEPROP 1 LAST WATTAGE 1/16W
J 0
(-710 3875);
DISPLAY 0.617021 (-710 3875);
PAINT SKYBLUE (-710 3875);
FORCEPROP 1 LAST TOLERANCE 1%
J 0
(-705 3925);
DISPLAY 0.617021 (-705 3925);
PAINT SKYBLUE (-705 3925);
FORCEPROP 1 LAST MATERIAL EMPTY
J 0
(-710 3825);
DISPLAY 0.617021 (-710 3825);
PAINT RED (-710 3825);
FORCEPROP 1 LAST PACK_TYPE 0402
J 0
(-710 3725);
DISPLAY 0.617021 (-710 3725);
PAINT SKYBLUE (-710 3725);
FORCEPROP 2 LAST CDS_SEC 1
J 0
(-700 4125);
PAINT MONO (-700 4125);
DISPLAY INVISIBLE (-700 4125);
FORCEPROP 2 LAST $SEC 1
J 0
(-700 4125);
PAINT MONO (-700 4125);
DISPLAY INVISIBLE (-700 4125);
FORCEPROP 1 LAST PATH I65
J 0
(-700 4075);
DISPLAY 0.978723 (-700 4075);
PAINT WHITE (-700 4075);
DISPLAY INVISIBLE (-700 4075);
FORCEPROP 1 LASTPIN (-750 4000) $PN 1
J 0
(-745 3962);
DISPLAY 0.787234 (-745 3962);
PAINT ORANGE (-745 3962);
DISPLAY INVISIBLE (-745 3962);
FORCEPROP 2 LAST CDS_LIB mstr_discrete
J 0
(-750 3900);
PAINT ORANGE (-750 3900);
DISPLAY INVISIBLE (-750 3900);
FORCEPROP 1 LASTPIN (-750 3800) $PN 2
J 0
(-745 3810);
DISPLAY 0.787234 (-745 3810);
PAINT ORANGE (-745 3810);
DISPLAY INVISIBLE (-745 3810);
FORCEADD GND..1
(-750 3700);
FORCEPROP 3 LASTPIN (-750 3750) SIG_NAME GND\g
J 0
(-740 3760);
DISPLAY 0.659574 (-740 3760);
PAINT MONO (-740 3760);
DISPLAY INVISIBLE (-740 3760);
FORCEPROP 1 LAST HDL_POWER GND
J 0
(-750 3850);
DISPLAY 1.723404 (-750 3850);
PAINT GREEN (-750 3850);
DISPLAY INVISIBLE (-750 3850);
FORCEPROP 1 LAST VOLTAGE 0
J 0
(-750 3700);
PAINT SKYBLUE (-750 3700);
DISPLAY INVISIBLE (-750 3700);
FORCEPROP 2 LAST CDS_LIB mstr_symbols
J 0
(-750 3700);
PAINT ORANGE (-750 3700);
DISPLAY INVISIBLE (-750 3700);
FORCEPROP 1 LAST SIZE 1B
J 0
(-675 3650);
DISPLAY 1.723404 (-675 3650);
PAINT GREEN (-675 3650);
DISPLAY INVISIBLE (-675 3650);
FORCEPROP 1 LAST PATH I66
J 0
(-675 3700);
DISPLAY 0.872340 (-675 3700);
PAINT AQUA (-675 3700);
DISPLAY INVISIBLE (-675 3700);
FORCEPROP 1 LAST BODY_TYPE PLUMBING
J 0
(-795 3657);
DISPLAY 0.340426 (-795 3657);
PAINT GREEN (-795 3657);
DISPLAY INVISIBLE (-795 3657);
FORCEPROP 2 LAST BOM_COST PROC_VRD_VCCIN_CPU0
J 0
(-1125 3775);
DISPLAY 1.446809 (-1125 3775);
PAINT MONO (-1125 3775);
DISPLAY INVISIBLE (-1125 3775);
FORCEPROP 2 LAST ROOM PVCCIN_CPU0_PWR_VR
J 0
(-1300 3775);
DISPLAY 1.936170 (-1300 3775);
PAINT ORANGE (-1300 3775);
DISPLAY INVISIBLE (-1300 3775);
FORCEADD RES..2
(-825 1350);
FORCEPROP 1 LAST LOCATION R4E19
J 0
(-780 1475);
DISPLAY 0.617021 (-780 1475);
PAINT AQUA (-780 1475);
FORCEPROP 1 LAST MATERIAL EMPTY
J 0
(-785 1275);
DISPLAY 0.617021 (-785 1275);
PAINT RED (-785 1275);
FORCEPROP 1 LAST TOLERANCE 1%
J 0
(-780 1375);
DISPLAY 0.617021 (-780 1375);
PAINT SKYBLUE (-780 1375);
FORCEPROP 1 LAST VALUE 68.1K
J 0
(-780 1425);
DISPLAY 0.617021 (-780 1425);
PAINT SKYBLUE (-780 1425);
FORCEPROP 1 LAST PACK_TYPE 0402
J 0
(-785 1175);
DISPLAY 0.617021 (-785 1175);
PAINT SKYBLUE (-785 1175);
FORCEPROP 1 LAST PART_NUMBER G21796-187
J 0
(-785 1225);
DISPLAY 0.617021 (-785 1225);
PAINT BLUE (-785 1225);
FORCEPROP 1 LAST WATTAGE 1/16W
J 0
(-785 1325);
DISPLAY 0.617021 (-785 1325);
PAINT SKYBLUE (-785 1325);
FORCEPROP 2 LAST CDS_SEC 1
J 0
(-775 1575);
PAINT MONO (-775 1575);
DISPLAY INVISIBLE (-775 1575);
FORCEPROP 2 LAST $SEC 1
J 0
(-775 1575);
PAINT MONO (-775 1575);
DISPLAY INVISIBLE (-775 1575);
FORCEPROP 1 LAST PATH I67
J 0
(-775 1525);
DISPLAY 0.978723 (-775 1525);
PAINT WHITE (-775 1525);
DISPLAY INVISIBLE (-775 1525);
FORCEPROP 1 LASTPIN (-825 1450) $PN 1
J 0
(-820 1412);
DISPLAY 0.787234 (-820 1412);
PAINT ORANGE (-820 1412);
DISPLAY INVISIBLE (-820 1412);
FORCEPROP 2 LAST CDS_LIB mstr_discrete
J 0
(-825 1350);
PAINT ORANGE (-825 1350);
DISPLAY INVISIBLE (-825 1350);
FORCEPROP 1 LASTPIN (-825 1250) $PN 2
J 0
(-820 1260);
DISPLAY 0.787234 (-820 1260);
PAINT ORANGE (-820 1260);
DISPLAY INVISIBLE (-820 1260);
FORCEADD GND..1
(-825 1150);
FORCEPROP 3 LASTPIN (-825 1200) SIG_NAME GND\g
J 0
(-815 1210);
DISPLAY 0.659574 (-815 1210);
PAINT MONO (-815 1210);
DISPLAY INVISIBLE (-815 1210);
FORCEPROP 1 LAST SIZE 1B
J 0
(-750 1100);
DISPLAY 1.723404 (-750 1100);
PAINT GREEN (-750 1100);
DISPLAY INVISIBLE (-750 1100);
FORCEPROP 1 LAST PATH I68
J 0
(-750 1150);
DISPLAY 0.872340 (-750 1150);
PAINT AQUA (-750 1150);
DISPLAY INVISIBLE (-750 1150);
FORCEPROP 1 LAST HDL_POWER GND
J 0
(-825 1300);
DISPLAY 1.723404 (-825 1300);
PAINT GREEN (-825 1300);
DISPLAY INVISIBLE (-825 1300);
FORCEPROP 1 LAST VOLTAGE 0
J 0
(-825 1150);
PAINT SKYBLUE (-825 1150);
DISPLAY INVISIBLE (-825 1150);
FORCEPROP 2 LAST CDS_LIB mstr_symbols
J 0
(-825 1150);
PAINT ORANGE (-825 1150);
DISPLAY INVISIBLE (-825 1150);
FORCEPROP 1 LAST BODY_TYPE PLUMBING
J 0
(-870 1107);
DISPLAY 0.340426 (-870 1107);
PAINT GREEN (-870 1107);
DISPLAY INVISIBLE (-870 1107);
FORCEPROP 2 LAST BOM_COST PROC_VRD_VCCIN_CPU0
J 0
(-1200 1225);
DISPLAY 1.446809 (-1200 1225);
PAINT MONO (-1200 1225);
DISPLAY INVISIBLE (-1200 1225);
FORCEPROP 2 LAST ROOM PVCCIN_CPU0_PWR_VR
J 0
(-1375 1225);
DISPLAY 1.936170 (-1375 1225);
PAINT ORANGE (-1375 1225);
DISPLAY INVISIBLE (-1375 1225);
FORCEADD CAP_A..1
(-4125 3300);
FORCEPROP 1 LAST VOLTAGE 16V
J 0
(-4075 3300);
DISPLAY 0.617021 (-4075 3300);
PAINT SKYBLUE (-4075 3300);
FORCEPROP 1 LAST PACK_TYPE 0402V
J 0
(-4075 3100);
DISPLAY 0.617021 (-4075 3100);
PAINT SKYBLUE (-4075 3100);
FORCEPROP 1 LAST PART_NUMBER A36096-030
J 0
(-4075 3150);
DISPLAY 0.617021 (-4075 3150);
PAINT BLUE (-4075 3150);
FORCEPROP 1 LAST MATERIAL X7R
J 0
(-4075 3200);
DISPLAY 0.617021 (-4075 3200);
PAINT SKYBLUE (-4075 3200);
FORCEPROP 1 LAST TOLERANCE 10%
J 0
(-4075 3250);
DISPLAY 0.617021 (-4075 3250);
PAINT SKYBLUE (-4075 3250);
FORCEPROP 1 LAST VALUE 0.1UF
J 0
(-4075 3350);
DISPLAY 0.617021 (-4075 3350);
PAINT SKYBLUE (-4075 3350);
FORCEPROP 0 LAST STATUS NOPOP
J 0
(-4350 3200);
DISPLAY 1.021277 (-4350 3200);
PAINT ORANGE (-4350 3200);
FORCEPROP 1 LAST LOCATION CT1
J 0
(-4275 3300);
DISPLAY 0.617021 (-4275 3300);
PAINT AQUA (-4275 3300);
FORCEPROP 1 LASTPIN (-4125 3200) $PN 2
J 0
(-4115 3180);
DISPLAY 0.787234 (-4115 3180);
PAINT ORANGE (-4115 3180);
DISPLAY INVISIBLE (-4115 3180);
FORCEPROP 1 LASTPIN (-4125 3400) $PN 1
J 0
(-4115 3380);
DISPLAY 0.787234 (-4115 3380);
PAINT ORANGE (-4115 3380);
DISPLAY INVISIBLE (-4115 3380);
FORCEPROP 2 LAST ROOM PVCCIN_CPU0_PWR_VR
J 0
(-4075 3450);
DISPLAY 1.361702 (-4075 3450);
PAINT ORANGE (-4075 3450);
DISPLAY INVISIBLE (-4075 3450);
FORCEPROP 1 LAST PATH I70
J 0
(-4075 3450);
DISPLAY 0.978723 (-4075 3450);
PAINT WHITE (-4075 3450);
DISPLAY INVISIBLE (-4075 3450);
FORCEPROP 2 LAST CDS_LIB dev_discrete
J 0
(-4125 3300);
PAINT MONO (-4125 3300);
DISPLAY INVISIBLE (-4125 3300);
FORCEADD GND..1
(-4125 3050);
FORCEPROP 3 LASTPIN (-4125 3100) SIG_NAME GND\g
J 0
(-4115 3110);
DISPLAY 0.659574 (-4115 3110);
PAINT MONO (-4115 3110);
DISPLAY INVISIBLE (-4115 3110);
FORCEPROP 1 LAST BODY_TYPE PLUMBING
J 0
(-4170 3007);
DISPLAY 0.340426 (-4170 3007);
PAINT GREEN (-4170 3007);
DISPLAY INVISIBLE (-4170 3007);
FORCEPROP 2 LAST ROOM PVCCIN_CPU0_PWR_VR
J 0
(-4675 3125);
DISPLAY 1.936170 (-4675 3125);
PAINT ORANGE (-4675 3125);
DISPLAY INVISIBLE (-4675 3125);
FORCEPROP 2 LAST BOM_COST PROC_VRD_VCCIN_CPU0
J 0
(-4500 3125);
DISPLAY 1.446809 (-4500 3125);
PAINT MONO (-4500 3125);
DISPLAY INVISIBLE (-4500 3125);
FORCEPROP 1 LAST SIZE 1B
J 0
(-4050 3000);
DISPLAY 1.723404 (-4050 3000);
PAINT GREEN (-4050 3000);
DISPLAY INVISIBLE (-4050 3000);
FORCEPROP 1 LAST VOLTAGE 0
J 0
(-4125 3050);
PAINT SKYBLUE (-4125 3050);
DISPLAY INVISIBLE (-4125 3050);
FORCEPROP 1 LAST HDL_POWER GND
J 0
(-4125 3200);
DISPLAY 1.723404 (-4125 3200);
PAINT GREEN (-4125 3200);
DISPLAY INVISIBLE (-4125 3200);
FORCEPROP 1 LAST PATH I71
J 0
(-4050 3050);
DISPLAY 0.872340 (-4050 3050);
PAINT AQUA (-4050 3050);
DISPLAY INVISIBLE (-4050 3050);
FORCEPROP 2 LAST CDS_LIB mstr_symbols
J 0
(-4125 3050);
PAINT MONO (-4125 3050);
DISPLAY INVISIBLE (-4125 3050);
FORCEADD GND..1
(-2350 3625);
FORCEPROP 3 LASTPIN (-2350 3675) SIG_NAME GND\g
J 0
(-2340 3685);
DISPLAY 0.659574 (-2340 3685);
PAINT MONO (-2340 3685);
DISPLAY INVISIBLE (-2340 3685);
FORCEPROP 1 LAST HDL_POWER GND
J 0
(-2350 3775);
DISPLAY 1.170213 (-2350 3775);
PAINT GREEN (-2350 3775);
DISPLAY INVISIBLE (-2350 3775);
FORCEPROP 1 LAST SIZE 1B
J 0
(-2275 3575);
DISPLAY 1.170213 (-2275 3575);
PAINT AQUA (-2275 3575);
DISPLAY INVISIBLE (-2275 3575);
FORCEPROP 1 LAST BODY_TYPE PLUMBING
J 0
(-2395 3582);
DISPLAY 0.340426 (-2395 3582);
PAINT GREEN (-2395 3582);
DISPLAY INVISIBLE (-2395 3582);
FORCEPROP 1 LAST VOLTAGE 0
J 0
(-2350 3625);
PAINT SKYBLUE (-2350 3625);
DISPLAY INVISIBLE (-2350 3625);
FORCEPROP 2 LAST ROOM VDDQ_KLM_PWR_VR
J 0
(-2925 3700);
DISPLAY 1.361702 (-2925 3700);
PAINT ORANGE (-2925 3700);
DISPLAY INVISIBLE (-2925 3700);
FORCEPROP 1 LAST PATH I73
J 0
(-2275 3625);
DISPLAY 0.872340 (-2275 3625);
PAINT AQUA (-2275 3625);
DISPLAY INVISIBLE (-2275 3625);
FORCEPROP 2 LAST CDS_LIB mstr_symbols
J 0
(-2350 3625);
PAINT MONO (-2350 3625);
DISPLAY INVISIBLE (-2350 3625);
FORCEADD 3D01R5F-GP..1
R 4
(-2550 3050);
FORCEPROP 0 LAST STATUS NOPOP
J 0
(-2500 2975);
DISPLAY 1.021277 (-2500 2975);
PAINT ORANGE (-2500 2975);
FORCEPROP 1 LAST VALUE 3D01R5F-GP
J 0
(-2500 3050);
DISPLAY 0.617021 (-2500 3050);
PAINT GREEN (-2500 3050);
FORCEPROP 1 LAST LOCATION RT2
J 0
(-2675 3045);
DISPLAY 0.617021 (-2675 3045);
PAINT GREEN (-2675 3045);
FORCEPROP 1 LAST CDS_LMAN_SYM_OUTLINE -50,75,50,-75
R 2
J 0
(-2550 3050);
DISPLAY 0.468085 (-2550 3050);
PAINT GREEN (-2550 3050);
DISPLAY INVISIBLE (-2550 3050);
FORCEPROP 1 LAST PATH I75
R 2
J 0
(-2550 3050);
DISPLAY 0.617021 (-2550 3050);
PAINT GREEN (-2550 3050);
DISPLAY INVISIBLE (-2550 3050);
FORCEPROP 2 LAST CDS_LIB w_hdl
J 0
(-2550 3050);
PAINT MONO (-2550 3050);
DISPLAY INVISIBLE (-2550 3050);
FORCEPROP 1 LAST PART_NUMBER 64.3R015.16L
R 2
J 0
(-2550 3050);
DISPLAY 0.617021 (-2550 3050);
PAINT GREEN (-2550 3050);
DISPLAY INVISIBLE (-2550 3050);
FORCEPROP 1 LAST PACK_TYPE SMD-RG5
R 2
J 0
(-2550 3050);
DISPLAY 0.617021 (-2550 3050);
PAINT GREEN (-2550 3050);
DISPLAY INVISIBLE (-2550 3050);
FORCEPROP 2 LASTPIN (-2550 3175) SIG_NAME UN$202$3D01R5F-GP$I75$2
J 0
(-2540 3185);
DISPLAY 0.659574 (-2540 3185);
PAINT MONO (-2540 3185);
DISPLAY INVISIBLE (-2540 3185);
FORCEADD SC2K2P50V3KX-GP..1
(-2550 3350);
FORCEPROP 0 LAST STATUS NOPOP
J 0
(-2425 3375);
DISPLAY 1.021277 (-2425 3375);
PAINT ORANGE (-2425 3375);
FORCEPROP 1 LAST LOCATION CT3
J 0
(-2525 3380);
DISPLAY 0.617021 (-2525 3380);
PAINT GREEN (-2525 3380);
FORCEPROP 1 LAST VALUE SC2K2P50V3KX-GP
J 0
(-2525 3300);
DISPLAY 0.617021 (-2525 3300);
PAINT GREEN (-2525 3300);
FORCEPROP 1 LAST PART_NUMBER 78.22224.2BL
J 0
(-2550 3350);
DISPLAY 0.617021 (-2550 3350);
PAINT GREEN (-2550 3350);
DISPLAY INVISIBLE (-2550 3350);
FORCEPROP 1 LAST PACK_TYPE SMD-BCG6
J 0
(-2550 3350);
DISPLAY 0.617021 (-2550 3350);
PAINT GREEN (-2550 3350);
DISPLAY INVISIBLE (-2550 3350);
FORCEPROP 1 LAST PATH I76
J 0
(-2550 3350);
DISPLAY 0.617021 (-2550 3350);
PAINT GREEN (-2550 3350);
DISPLAY INVISIBLE (-2550 3350);
FORCEPROP 1 LAST CDS_LMAN_SYM_OUTLINE -50,25,50,-25
J 0
(-2550 3350);
DISPLAY 0.468085 (-2550 3350);
PAINT GREEN (-2550 3350);
DISPLAY INVISIBLE (-2550 3350);
FORCEPROP 2 LAST CDS_LIB w_hdl
J 0
(-2550 3350);
PAINT MONO (-2550 3350);
DISPLAY INVISIBLE (-2550 3350);
FORCEADD GND..1
(-2550 2800);
FORCEPROP 3 LASTPIN (-2550 2850) SIG_NAME GND\g
J 0
(-2540 2860);
DISPLAY 0.659574 (-2540 2860);
PAINT MONO (-2540 2860);
DISPLAY INVISIBLE (-2540 2860);
FORCEPROP 1 LAST HDL_POWER GND
J 0
(-2550 2950);
DISPLAY 1.723404 (-2550 2950);
PAINT GREEN (-2550 2950);
DISPLAY INVISIBLE (-2550 2950);
FORCEPROP 1 LAST SIZE 1B
J 0
(-2475 2750);
DISPLAY 1.723404 (-2475 2750);
PAINT GREEN (-2475 2750);
DISPLAY INVISIBLE (-2475 2750);
FORCEPROP 1 LAST VOLTAGE 0
J 0
(-2550 2800);
PAINT SKYBLUE (-2550 2800);
DISPLAY INVISIBLE (-2550 2800);
FORCEPROP 1 LAST BODY_TYPE PLUMBING
J 0
(-2595 2757);
DISPLAY 0.340426 (-2595 2757);
PAINT GREEN (-2595 2757);
DISPLAY INVISIBLE (-2595 2757);
FORCEPROP 2 LAST BOM_COST PROC_VRD_VCCIN_CPU0
J 0
(-2925 2875);
DISPLAY 1.446809 (-2925 2875);
PAINT MONO (-2925 2875);
DISPLAY INVISIBLE (-2925 2875);
FORCEPROP 2 LAST ROOM PVCCIN_CPU0_PWR_VR
J 0
(-3100 2875);
DISPLAY 1.936170 (-3100 2875);
PAINT ORANGE (-3100 2875);
DISPLAY INVISIBLE (-3100 2875);
FORCEPROP 1 LAST PATH I77
J 0
(-2475 2800);
DISPLAY 0.872340 (-2475 2800);
PAINT AQUA (-2475 2800);
DISPLAY INVISIBLE (-2475 2800);
FORCEPROP 2 LAST CDS_LIB mstr_symbols
J 0
(-2550 2800);
PAINT MONO (-2550 2800);
DISPLAY INVISIBLE (-2550 2800);
FORCEADD CAP..1
(-2350 3875);
FORCEPROP 1 LAST PART_NUMBER A36096-046
J 0
(-2300 3725);
DISPLAY 0.617021 (-2300 3725);
PAINT BLUE (-2300 3725);
FORCEPROP 1 LAST MATERIAL X7R
J 0
(-2300 3775);
DISPLAY 0.617021 (-2300 3775);
PAINT SKYBLUE (-2300 3775);
FORCEPROP 1 LAST VOLTAGE 50V
J 0
(-2300 3875);
DISPLAY 0.617021 (-2300 3875);
PAINT SKYBLUE (-2300 3875);
FORCEPROP 0 LAST STATUS NOPOP
J 0
(-2675 3850);
DISPLAY 1.021277 (-2675 3850);
PAINT ORANGE (-2675 3850);
FORCEPROP 1 LAST TOLERANCE 10%
J 0
(-2300 3825);
DISPLAY 0.617021 (-2300 3825);
PAINT SKYBLUE (-2300 3825);
FORCEPROP 1 LASTPIN (-2350 3775) $PN 2
J 0
(-2340 3755);
DISPLAY 0.617021 (-2340 3755);
PAINT ORANGE (-2340 3755);
FORCEPROP 1 LASTPIN (-2350 3975) $PN 1
J 0
(-2340 3955);
DISPLAY 0.617021 (-2340 3955);
PAINT ORANGE (-2340 3955);
FORCEPROP 1 LAST PACK_TYPE 0402LF
J 0
(-2300 3675);
DISPLAY 0.617021 (-2300 3675);
PAINT SKYBLUE (-2300 3675);
FORCEPROP 1 LAST LOCATION CT2
J 0
(-2300 3975);
DISPLAY 0.617021 (-2300 3975);
PAINT AQUA (-2300 3975);
FORCEPROP 1 LAST VALUE 1000PF
J 0
(-2300 3925);
DISPLAY 0.617021 (-2300 3925);
PAINT SKYBLUE (-2300 3925);
FORCEPROP 0 LAST ROOM VDDQ_KLM_PWR_VR
J 0
(-2300 4075);
DISPLAY 1.021277 (-2300 4075);
PAINT ORANGE (-2300 4075);
DISPLAY INVISIBLE (-2300 4075);
FORCEPROP 1 LAST PATH I78
J 0
(-2300 4025);
DISPLAY 0.978723 (-2300 4025);
PAINT WHITE (-2300 4025);
DISPLAY INVISIBLE (-2300 4025);
FORCEPROP 2 LAST SEC 1
J 0
(-2300 4075);
DISPLAY 0.680851 (-2300 4075);
PAINT MONO (-2300 4075);
DISPLAY INVISIBLE (-2300 4075);
FORCEPROP 2 LAST SEC_TYPE 0402LF
J 0
(-2300 4075);
DISPLAY 1.021277 (-2300 4075);
PAINT ORANGE (-2300 4075);
DISPLAY INVISIBLE (-2300 4075);
FORCEPROP 2 LAST CDS_LIB mstr_discrete
J 0
(-2350 3875);
PAINT MONO (-2350 3875);
DISPLAY INVISIBLE (-2350 3875);
FORCEPROP 2 LAST CDS_LOCATION CT2
J 0
(-2300 3975);
DISPLAY 0.617021 (-2300 3975);
PAINT AQUA (-2300 3975);
DISPLAY INVISIBLE (-2300 3975);
FORCEADD GND..1
(-1000 3000);
FORCEPROP 3 LASTPIN (-1000 3050) SIG_NAME GND\g
J 0
(-990 3060);
DISPLAY 0.659574 (-990 3060);
PAINT MONO (-990 3060);
DISPLAY INVISIBLE (-990 3060);
FORCEPROP 1 LAST BODY_TYPE PLUMBING
J 0
(-1045 2957);
DISPLAY 0.340426 (-1045 2957);
PAINT GREEN (-1045 2957);
DISPLAY INVISIBLE (-1045 2957);
FORCEPROP 2 LAST ROOM PVCCIN_CPU0_PWR_VR
J 0
(-1550 3075);
DISPLAY 1.936170 (-1550 3075);
PAINT ORANGE (-1550 3075);
DISPLAY INVISIBLE (-1550 3075);
FORCEPROP 2 LAST BOM_COST PROC_VRD_VCCIN_CPU0
J 0
(-1375 3075);
DISPLAY 1.446809 (-1375 3075);
PAINT MONO (-1375 3075);
DISPLAY INVISIBLE (-1375 3075);
FORCEPROP 1 LAST SIZE 1B
J 0
(-925 2950);
DISPLAY 1.723404 (-925 2950);
PAINT GREEN (-925 2950);
DISPLAY INVISIBLE (-925 2950);
FORCEPROP 1 LAST VOLTAGE 0
J 0
(-1000 3000);
PAINT SKYBLUE (-1000 3000);
DISPLAY INVISIBLE (-1000 3000);
FORCEPROP 1 LAST HDL_POWER GND
J 0
(-1000 3150);
DISPLAY 1.723404 (-1000 3150);
PAINT GREEN (-1000 3150);
DISPLAY INVISIBLE (-1000 3150);
FORCEPROP 1 LAST PATH I8
J 0
(-925 3000);
DISPLAY 0.872340 (-925 3000);
PAINT AQUA (-925 3000);
DISPLAY INVISIBLE (-925 3000);
FORCEPROP 2 LAST CDS_LIB mstr_symbols
J 0
(-1000 3000);
DISPLAY 1.936170 (-1000 3000);
PAINT ORANGE (-1000 3000);
DISPLAY INVISIBLE (-1000 3000);
FORCEADD GND..1
(-4175 425);
FORCEPROP 3 LASTPIN (-4175 475) SIG_NAME GND\g
J 0
(-4165 485);
DISPLAY 0.659574 (-4165 485);
PAINT MONO (-4165 485);
DISPLAY INVISIBLE (-4165 485);
FORCEPROP 1 LAST BODY_TYPE PLUMBING
J 0
(-4220 382);
DISPLAY 0.340426 (-4220 382);
PAINT GREEN (-4220 382);
DISPLAY INVISIBLE (-4220 382);
FORCEPROP 2 LAST ROOM PVCCIN_CPU0_PWR_VR
J 0
(-4725 500);
DISPLAY 1.936170 (-4725 500);
PAINT ORANGE (-4725 500);
DISPLAY INVISIBLE (-4725 500);
FORCEPROP 2 LAST BOM_COST PROC_VRD_VCCIN_CPU0
J 0
(-4550 500);
DISPLAY 1.446809 (-4550 500);
PAINT MONO (-4550 500);
DISPLAY INVISIBLE (-4550 500);
FORCEPROP 1 LAST SIZE 1B
J 0
(-4100 375);
DISPLAY 1.723404 (-4100 375);
PAINT GREEN (-4100 375);
DISPLAY INVISIBLE (-4100 375);
FORCEPROP 1 LAST VOLTAGE 0
J 0
(-4175 425);
PAINT SKYBLUE (-4175 425);
DISPLAY INVISIBLE (-4175 425);
FORCEPROP 1 LAST HDL_POWER GND
J 0
(-4175 575);
DISPLAY 1.723404 (-4175 575);
PAINT GREEN (-4175 575);
DISPLAY INVISIBLE (-4175 575);
FORCEPROP 1 LAST PATH I80
J 0
(-4100 425);
DISPLAY 0.872340 (-4100 425);
PAINT AQUA (-4100 425);
DISPLAY INVISIBLE (-4100 425);
FORCEPROP 2 LAST CDS_LIB mstr_symbols
J 0
(-4175 425);
PAINT MONO (-4175 425);
DISPLAY INVISIBLE (-4175 425);
FORCEADD CAP_A..1
(-4175 675);
FORCEPROP 0 LAST STATUS NOPOP
J 0
(-4400 575);
DISPLAY 1.021277 (-4400 575);
PAINT ORANGE (-4400 575);
FORCEPROP 1 LAST MATERIAL X7R
J 0
(-4125 575);
DISPLAY 0.617021 (-4125 575);
PAINT SKYBLUE (-4125 575);
FORCEPROP 1 LAST VALUE 0.1UF
J 0
(-4125 725);
DISPLAY 0.617021 (-4125 725);
PAINT SKYBLUE (-4125 725);
FORCEPROP 1 LAST LOCATION CT6
J 0
(-4125 750);
DISPLAY 0.617021 (-4125 750);
PAINT AQUA (-4125 750);
FORCEPROP 1 LAST VOLTAGE 16V
J 0
(-4125 675);
DISPLAY 0.617021 (-4125 675);
PAINT SKYBLUE (-4125 675);
FORCEPROP 1 LAST TOLERANCE 10%
J 0
(-4125 625);
DISPLAY 0.617021 (-4125 625);
PAINT SKYBLUE (-4125 625);
FORCEPROP 1 LAST PACK_TYPE 0402V
J 0
(-4125 475);
DISPLAY 0.617021 (-4125 475);
PAINT SKYBLUE (-4125 475);
FORCEPROP 1 LAST PART_NUMBER A36096-030
J 0
(-4125 525);
DISPLAY 0.617021 (-4125 525);
PAINT BLUE (-4125 525);
FORCEPROP 1 LASTPIN (-4175 575) $PN 2
J 0
(-4165 555);
DISPLAY 0.787234 (-4165 555);
PAINT ORANGE (-4165 555);
DISPLAY INVISIBLE (-4165 555);
FORCEPROP 1 LASTPIN (-4175 775) $PN 1
J 0
(-4165 755);
DISPLAY 0.787234 (-4165 755);
PAINT ORANGE (-4165 755);
DISPLAY INVISIBLE (-4165 755);
FORCEPROP 2 LAST ROOM PVCCIN_CPU0_PWR_VR
J 0
(-4125 825);
DISPLAY 1.361702 (-4125 825);
PAINT ORANGE (-4125 825);
DISPLAY INVISIBLE (-4125 825);
FORCEPROP 1 LAST PATH I81
J 0
(-4125 825);
DISPLAY 0.978723 (-4125 825);
PAINT WHITE (-4125 825);
DISPLAY INVISIBLE (-4125 825);
FORCEPROP 2 LAST CDS_LIB dev_discrete
J 0
(-4175 675);
PAINT MONO (-4175 675);
DISPLAY INVISIBLE (-4175 675);
FORCEADD SC2K2P50V3KX-GP..1
(-2450 800);
FORCEPROP 0 LAST STATUS NOPOP
J 0
(-2325 825);
DISPLAY 1.021277 (-2325 825);
PAINT ORANGE (-2325 825);
FORCEPROP 1 LAST LOCATION CT5
J 0
(-2425 830);
DISPLAY 0.617021 (-2425 830);
PAINT GREEN (-2425 830);
FORCEPROP 1 LAST VALUE SC2K2P50V3KX-GP
J 0
(-2425 750);
DISPLAY 0.617021 (-2425 750);
PAINT GREEN (-2425 750);
FORCEPROP 1 LAST PACK_TYPE SMD-BCG6
J 0
(-2450 800);
DISPLAY 0.617021 (-2450 800);
PAINT GREEN (-2450 800);
DISPLAY INVISIBLE (-2450 800);
FORCEPROP 1 LAST PART_NUMBER 78.22224.2BL
J 0
(-2450 800);
DISPLAY 0.617021 (-2450 800);
PAINT GREEN (-2450 800);
DISPLAY INVISIBLE (-2450 800);
FORCEPROP 1 LAST CDS_LMAN_SYM_OUTLINE -50,25,50,-25
J 0
(-2450 800);
DISPLAY 0.468085 (-2450 800);
PAINT GREEN (-2450 800);
DISPLAY INVISIBLE (-2450 800);
FORCEPROP 1 LAST PATH I82
J 0
(-2450 800);
DISPLAY 0.617021 (-2450 800);
PAINT GREEN (-2450 800);
DISPLAY INVISIBLE (-2450 800);
FORCEPROP 2 LAST CDS_LIB w_hdl
J 0
(-2450 800);
PAINT MONO (-2450 800);
DISPLAY INVISIBLE (-2450 800);
FORCEADD 3D01R5F-GP..1
R 4
(-2450 575);
FORCEPROP 1 LAST LOCATION RT4
J 0
(-2575 595);
DISPLAY 0.617021 (-2575 595);
PAINT GREEN (-2575 595);
FORCEPROP 1 LAST VALUE 3D01R5F-GP
J 0
(-2725 550);
DISPLAY 0.617021 (-2725 550);
PAINT GREEN (-2725 550);
FORCEPROP 0 LAST STATUS NOPOP
J 0
(-2400 575);
DISPLAY 1.021277 (-2400 575);
PAINT ORANGE (-2400 575);
FORCEPROP 1 LAST CDS_LMAN_SYM_OUTLINE -50,75,50,-75
R 2
J 0
(-2450 575);
DISPLAY 0.468085 (-2450 575);
PAINT GREEN (-2450 575);
DISPLAY INVISIBLE (-2450 575);
FORCEPROP 1 LAST PATH I83
R 2
J 0
(-2450 575);
DISPLAY 0.617021 (-2450 575);
PAINT GREEN (-2450 575);
DISPLAY INVISIBLE (-2450 575);
FORCEPROP 2 LAST CDS_LIB w_hdl
J 0
(-2450 575);
PAINT MONO (-2450 575);
DISPLAY INVISIBLE (-2450 575);
FORCEPROP 1 LAST PART_NUMBER 64.3R015.16L
R 2
J 0
(-2450 575);
DISPLAY 0.617021 (-2450 575);
PAINT GREEN (-2450 575);
DISPLAY INVISIBLE (-2450 575);
FORCEPROP 1 LAST PACK_TYPE SMD-RG5
R 2
J 0
(-2450 575);
DISPLAY 0.617021 (-2450 575);
PAINT GREEN (-2450 575);
DISPLAY INVISIBLE (-2450 575);
FORCEPROP 2 LASTPIN (-2450 700) SIG_NAME UN$202$3D01R5F-GP$I83$2
J 0
(-2440 710);
DISPLAY 0.659574 (-2440 710);
PAINT MONO (-2440 710);
DISPLAY INVISIBLE (-2440 710);
FORCEADD GND..1
(-2450 375);
FORCEPROP 3 LASTPIN (-2450 425) SIG_NAME GND\g
J 0
(-2440 435);
DISPLAY 0.659574 (-2440 435);
PAINT MONO (-2440 435);
DISPLAY INVISIBLE (-2440 435);
FORCEPROP 2 LAST CDS_LIB mstr_symbols
J 0
(-2450 375);
PAINT MONO (-2450 375);
DISPLAY INVISIBLE (-2450 375);
FORCEPROP 1 LAST PATH I84
J 0
(-2375 375);
DISPLAY 0.872340 (-2375 375);
PAINT AQUA (-2375 375);
DISPLAY INVISIBLE (-2375 375);
FORCEPROP 1 LAST HDL_POWER GND
J 0
(-2450 525);
DISPLAY 1.723404 (-2450 525);
PAINT GREEN (-2450 525);
DISPLAY INVISIBLE (-2450 525);
FORCEPROP 1 LAST SIZE 1B
J 0
(-2375 325);
DISPLAY 1.723404 (-2375 325);
PAINT GREEN (-2375 325);
DISPLAY INVISIBLE (-2375 325);
FORCEPROP 1 LAST VOLTAGE 0
J 0
(-2450 375);
PAINT SKYBLUE (-2450 375);
DISPLAY INVISIBLE (-2450 375);
FORCEPROP 1 LAST BODY_TYPE PLUMBING
J 0
(-2495 332);
DISPLAY 0.340426 (-2495 332);
PAINT GREEN (-2495 332);
DISPLAY INVISIBLE (-2495 332);
FORCEPROP 2 LAST BOM_COST PROC_VRD_VCCIN_CPU0
J 0
(-2825 450);
DISPLAY 1.446809 (-2825 450);
PAINT MONO (-2825 450);
DISPLAY INVISIBLE (-2825 450);
FORCEPROP 2 LAST ROOM PVCCIN_CPU0_PWR_VR
J 0
(-3000 450);
DISPLAY 1.936170 (-3000 450);
PAINT ORANGE (-3000 450);
DISPLAY INVISIBLE (-3000 450);
FORCEADD GND..1
(-2450 1050);
FORCEPROP 3 LASTPIN (-2450 1100) SIG_NAME GND\g
J 0
(-2440 1110);
DISPLAY 0.659574 (-2440 1110);
PAINT MONO (-2440 1110);
DISPLAY INVISIBLE (-2440 1110);
FORCEPROP 1 LAST HDL_POWER GND
J 0
(-2450 1200);
DISPLAY 1.170213 (-2450 1200);
PAINT GREEN (-2450 1200);
DISPLAY INVISIBLE (-2450 1200);
FORCEPROP 1 LAST SIZE 1B
J 0
(-2375 1000);
DISPLAY 1.170213 (-2375 1000);
PAINT AQUA (-2375 1000);
DISPLAY INVISIBLE (-2375 1000);
FORCEPROP 1 LAST BODY_TYPE PLUMBING
J 0
(-2495 1007);
DISPLAY 0.340426 (-2495 1007);
PAINT GREEN (-2495 1007);
DISPLAY INVISIBLE (-2495 1007);
FORCEPROP 1 LAST VOLTAGE 0
J 0
(-2450 1050);
PAINT SKYBLUE (-2450 1050);
DISPLAY INVISIBLE (-2450 1050);
FORCEPROP 2 LAST ROOM VDDQ_KLM_PWR_VR
J 0
(-3025 1125);
DISPLAY 1.361702 (-3025 1125);
PAINT ORANGE (-3025 1125);
DISPLAY INVISIBLE (-3025 1125);
FORCEPROP 1 LAST PATH I86
J 0
(-2375 1050);
DISPLAY 0.872340 (-2375 1050);
PAINT AQUA (-2375 1050);
DISPLAY INVISIBLE (-2375 1050);
FORCEPROP 2 LAST CDS_LIB mstr_symbols
J 0
(-2450 1050);
PAINT MONO (-2450 1050);
DISPLAY INVISIBLE (-2450 1050);
FORCEADD CAP..1
(-2450 1250);
FORCEPROP 0 LAST STATUS NOPOP
J 0
(-2300 1200);
DISPLAY 1.021277 (-2300 1200);
PAINT ORANGE (-2300 1200);
FORCEPROP 1 LAST PART_NUMBER A36096-046
J 0
(-2400 1100);
DISPLAY 0.617021 (-2400 1100);
PAINT BLUE (-2400 1100);
FORCEPROP 1 LAST LOCATION CT4
J 0
(-2600 1250);
DISPLAY 0.617021 (-2600 1250);
PAINT AQUA (-2600 1250);
FORCEPROP 1 LAST VALUE 1000PF
J 0
(-2400 1300);
DISPLAY 0.617021 (-2400 1300);
PAINT SKYBLUE (-2400 1300);
FORCEPROP 1 LAST VOLTAGE 50V
J 0
(-2400 1250);
DISPLAY 0.617021 (-2400 1250);
PAINT SKYBLUE (-2400 1250);
FORCEPROP 1 LAST TOLERANCE 10%
J 0
(-2400 1200);
DISPLAY 0.617021 (-2400 1200);
PAINT SKYBLUE (-2400 1200);
FORCEPROP 1 LAST PACK_TYPE 0402LF
J 0
(-2400 1050);
DISPLAY 0.617021 (-2400 1050);
PAINT SKYBLUE (-2400 1050);
FORCEPROP 1 LAST MATERIAL X7R
J 0
(-2400 1150);
DISPLAY 0.617021 (-2400 1150);
PAINT SKYBLUE (-2400 1150);
FORCEPROP 1 LASTPIN (-2450 1350) $PN 1
J 0
(-2440 1330);
DISPLAY 0.787234 (-2440 1330);
PAINT ORANGE (-2440 1330);
DISPLAY INVISIBLE (-2440 1330);
FORCEPROP 1 LASTPIN (-2450 1150) $PN 2
J 0
(-2440 1130);
DISPLAY 0.787234 (-2440 1130);
PAINT ORANGE (-2440 1130);
DISPLAY INVISIBLE (-2440 1130);
FORCEPROP 2 LAST CDS_LIB mstr_discrete
J 0
(-2450 1250);
PAINT MONO (-2450 1250);
DISPLAY INVISIBLE (-2450 1250);
FORCEPROP 0 LAST ROOM VDDQ_KLM_PWR_VR
J 0
(-2400 1450);
DISPLAY 1.021277 (-2400 1450);
PAINT ORANGE (-2400 1450);
DISPLAY INVISIBLE (-2400 1450);
FORCEPROP 0 LAST $SEC 1
J 0
(-2400 1350);
PAINT MONO (-2400 1350);
DISPLAY INVISIBLE (-2400 1350);
FORCEPROP 0 LAST CDS_SEC 1
J 0
(-2400 1350);
PAINT MONO (-2400 1350);
DISPLAY INVISIBLE (-2400 1350);
FORCEPROP 1 LAST PATH I87
J 0
(-2400 1400);
DISPLAY 0.978723 (-2400 1400);
PAINT WHITE (-2400 1400);
DISPLAY INVISIBLE (-2400 1400);
FORCEPROP 0 LAST CDS_LOCATION CT4
J 0
(-2400 1350);
PAINT MONO (-2400 1350);
DISPLAY INVISIBLE (-2400 1350);
FORCEADD RES..1
(-4925 3575);
FORCEPROP 1 LAST PACK_TYPE 0402
J 0
(-4850 3425);
DISPLAY 0.617021 (-4850 3425);
PAINT SKYBLUE (-4850 3425);
FORCEPROP 1 LAST MATERIAL CHIP
J 0
(-4950 3425);
DISPLAY 0.617021 (-4950 3425);
PAINT SKYBLUE (-4950 3425);
FORCEPROP 1 LAST PART_NUMBER G21497-005
J 0
(-5025 3525);
DISPLAY 0.617021 (-5025 3525);
PAINT BLUE (-5025 3525);
FORCEPROP 1 LAST LOCATION RT1
J 0
(-4975 3625);
DISPLAY 0.617021 (-4975 3625);
PAINT AQUA (-4975 3625);
FORCEPROP 1 LAST WATTAGE 1/16W
J 2
(-4950 3425);
DISPLAY 0.617021 (-4950 3425);
PAINT SKYBLUE (-4950 3425);
FORCEPROP 1 LAST VALUE 0.0
J 2
(-4950 3475);
DISPLAY 0.617021 (-4950 3475);
PAINT SKYBLUE (-4950 3475);
FORCEPROP 1 LAST TOLERANCE 5%
J 0
(-4925 3475);
DISPLAY 0.617021 (-4925 3475);
PAINT SKYBLUE (-4925 3475);
FORCEPROP 2 LAST ROOM BMC_DEBUG_HEADER
J 0
(-4975 3725);
DISPLAY 1.021277 (-4975 3725);
PAINT ORANGE (-4975 3725);
DISPLAY INVISIBLE (-4975 3725);
FORCEPROP 2 LAST BOM_COST DEBUG
J 0
(-4975 3775);
DISPLAY 1.021277 (-4975 3775);
PAINT ORANGE (-4975 3775);
DISPLAY INVISIBLE (-4975 3775);
FORCEPROP 1 LAST PATH I88
J 0
(-4975 3725);
DISPLAY 0.978723 (-4975 3725);
PAINT WHITE (-4975 3725);
DISPLAY INVISIBLE (-4975 3725);
FORCEPROP 2 LAST CDS_LIB mstr_discrete
J 0
(-4925 3575);
PAINT MONO (-4925 3575);
DISPLAY INVISIBLE (-4925 3575);
FORCEPROP 1 LASTPIN (-5025 3575) $PN 1
J 0
(-5013 3587);
DISPLAY 0.787234 (-5013 3587);
PAINT ORANGE (-5013 3587);
DISPLAY INVISIBLE (-5013 3587);
FORCEPROP 1 LASTPIN (-4825 3575) $PN 2
J 0
(-4863 3587);
DISPLAY 0.787234 (-4863 3587);
PAINT ORANGE (-4863 3587);
DISPLAY INVISIBLE (-4863 3587);
FORCEADD RES..1
(-4975 950);
FORCEPROP 1 LAST PART_NUMBER G21497-005
J 0
(-5075 900);
DISPLAY 0.617021 (-5075 900);
PAINT BLUE (-5075 900);
FORCEPROP 1 LAST PACK_TYPE 0402
J 0
(-4925 800);
DISPLAY 0.617021 (-4925 800);
PAINT SKYBLUE (-4925 800);
FORCEPROP 1 LAST TOLERANCE 5%
J 0
(-4975 850);
DISPLAY 0.617021 (-4975 850);
PAINT SKYBLUE (-4975 850);
FORCEPROP 1 LAST MATERIAL CHIP
J 0
(-5025 800);
DISPLAY 0.617021 (-5025 800);
PAINT SKYBLUE (-5025 800);
FORCEPROP 1 LAST VALUE 0.0
J 2
(-5000 850);
DISPLAY 0.617021 (-5000 850);
PAINT SKYBLUE (-5000 850);
FORCEPROP 1 LAST WATTAGE 1/16W
J 2
(-5025 800);
DISPLAY 0.617021 (-5025 800);
PAINT SKYBLUE (-5025 800);
FORCEPROP 1 LAST LOCATION RT3
J 0
(-5025 1000);
DISPLAY 0.617021 (-5025 1000);
PAINT AQUA (-5025 1000);
FORCEPROP 2 LAST CDS_LIB mstr_discrete
J 0
(-4975 950);
PAINT MONO (-4975 950);
DISPLAY INVISIBLE (-4975 950);
FORCEPROP 1 LAST PATH I89
J 0
(-5025 1100);
DISPLAY 0.978723 (-5025 1100);
PAINT WHITE (-5025 1100);
DISPLAY INVISIBLE (-5025 1100);
FORCEPROP 2 LAST ROOM BMC_DEBUG_HEADER
J 0
(-5025 1100);
DISPLAY 1.021277 (-5025 1100);
PAINT ORANGE (-5025 1100);
DISPLAY INVISIBLE (-5025 1100);
FORCEPROP 2 LAST BOM_COST DEBUG
J 0
(-5025 1150);
DISPLAY 1.021277 (-5025 1150);
PAINT ORANGE (-5025 1150);
DISPLAY INVISIBLE (-5025 1150);
FORCEPROP 1 LASTPIN (-5075 950) $PN 1
J 0
(-5063 962);
DISPLAY 0.787234 (-5063 962);
PAINT ORANGE (-5063 962);
DISPLAY INVISIBLE (-5063 962);
FORCEPROP 1 LASTPIN (-4875 950) $PN 2
J 0
(-4913 962);
DISPLAY 0.787234 (-4913 962);
PAINT ORANGE (-4913 962);
DISPLAY INVISIBLE (-4913 962);
FORCEADD CAP_A..1
(-1250 3300);
FORCEPROP 1 LAST LOCATION C6R7
J 0
(-1200 3400);
DISPLAY 0.617021 (-1200 3400);
PAINT AQUA (-1200 3400);
FORCEPROP 1 LAST VALUE 22.0UF
J 0
(-1200 3350);
DISPLAY 0.617021 (-1200 3350);
PAINT SKYBLUE (-1200 3350);
FORCEPROP 1 LASTPIN (-1250 3400) $PN 1
J 0
(-1240 3380);
DISPLAY 0.617021 (-1240 3380);
PAINT GREEN (-1240 3380);
FORCEPROP 1 LAST TOLERANCE 20%
J 0
(-1200 3250);
DISPLAY 0.617021 (-1200 3250);
PAINT SKYBLUE (-1200 3250);
FORCEPROP 1 LAST PACK_TYPE 0603V
J 0
(-1200 3100);
DISPLAY 0.617021 (-1200 3100);
PAINT SKYBLUE (-1200 3100);
FORCEPROP 1 LAST VOLTAGE 4V
J 0
(-1200 3300);
DISPLAY 0.617021 (-1200 3300);
PAINT SKYBLUE (-1200 3300);
FORCEPROP 1 LAST MATERIAL X6S
J 0
(-1200 3200);
DISPLAY 0.617021 (-1200 3200);
PAINT SKYBLUE (-1200 3200);
FORCEPROP 1 LAST PART_NUMBER E15431-004
J 0
(-1200 3150);
DISPLAY 0.617021 (-1200 3150);
PAINT BLUE (-1200 3150);
FORCEPROP 1 LASTPIN (-1250 3200) $PN 2
J 0
(-1240 3180);
DISPLAY 0.617021 (-1240 3180);
PAINT GREEN (-1240 3180);
FORCEPROP 2 LAST SEC_TYPE 0603V
J 0
(-1195 3500);
DISPLAY 1.021277 (-1195 3500);
PAINT ORANGE (-1195 3500);
DISPLAY INVISIBLE (-1195 3500);
FORCEPROP 2 LAST SEC 1
J 0
(-1195 3500);
DISPLAY 0.680851 (-1195 3500);
PAINT MONO (-1195 3500);
DISPLAY INVISIBLE (-1195 3500);
FORCEPROP 2 LAST BOM_COST PROC_VRD_VCCIN_CPU0
J 0
(-1200 3450);
DISPLAY 1.446809 (-1200 3450);
PAINT MONO (-1200 3450);
DISPLAY INVISIBLE (-1200 3450);
FORCEPROP 2 LAST CDS_SEC 1
J 0
(-1200 3450);
PAINT ORANGE (-1200 3450);
DISPLAY INVISIBLE (-1200 3450);
FORCEPROP 1 LAST PATH I9
J 0
(-1200 3450);
DISPLAY 0.978723 (-1200 3450);
PAINT WHITE (-1200 3450);
DISPLAY INVISIBLE (-1200 3450);
FORCEPROP 2 LAST ROOM PVCCIN_CPU0_PWR_VR
J 0
(-1200 3450);
DISPLAY 1.446809 (-1200 3450);
PAINT MONO (-1200 3450);
DISPLAY INVISIBLE (-1200 3450);
FORCEPROP 2 LAST CDS_LOCATION C6R7
J 0
(-1200 3400);
DISPLAY 0.617021 (-1200 3400);
PAINT AQUA (-1200 3400);
DISPLAY INVISIBLE (-1200 3400);
FORCEPROP 2 LAST CDS_LIB dev_discrete
J 0
(-1250 3300);
PAINT ORANGE (-1250 3300);
DISPLAY INVISIBLE (-1250 3300);
FORCEADD DNS..2
(-745 3895);
PAINT RED (-745 3895);
FORCEPROP 2 LAST CDS_LIB mstr_misc
J 0
(-745 3895);
PAINT ORANGE (-745 3895);
DISPLAY INVISIBLE (-745 3895);
FORCEPROP 1 LAST COMMENT_BODY TRUE
R 1
J 0
(-670 3670);
DISPLAY 0.872340 (-670 3670);
PAINT GREEN (-670 3670);
DISPLAY INVISIBLE (-670 3670);
FORCEADD DNS..2
(-820 1345);
PAINT RED (-820 1345);
FORCEPROP 2 LAST CDS_LIB mstr_misc
J 0
(-820 1345);
PAINT ORANGE (-820 1345);
DISPLAY INVISIBLE (-820 1345);
FORCEPROP 1 LAST COMMENT_BODY TRUE
R 1
J 0
(-745 1120);
DISPLAY 0.872340 (-745 1120);
PAINT GREEN (-745 1120);
DISPLAY INVISIBLE (-745 1120);
FORCEADD INTEL_CORP_BPAGE..1
(0 0);
FORCEPROP 1 LAST CDS_CON_LAST_MODIFIED Tue Dec 01 11:52:21 2015
J 0
(-1425 325);
PAINT ORANGE (-1425 325);
DISPLAY INVISIBLE (-1425 325);
FORCEPROP 1 LAST CUSTOM_TXT_CDS <CURRENT_DESIGN_SHEET> OF <TOTAL_DESIGN_SHEETS>
J 0
(-500 25);
PAINT GREEN (-500 25);
FORCEPROP 2 LAST CUSTOM_TXT_CDS <XR_PAGE_TITLE>
J 0
(-7890 5250);
DISPLAY 0.638298 (-7890 5250);
PAINT PINK (-7890 5250);
DISPLAY INVISIBLE (-7890 5250);
FORCEPROP 2 LAST CUSTOM_TXT_CDS <CON_LAST_MODIFIED>
J 0
(-3325 100);
PAINT ORANGE (-3325 100);
FORCEPROP 1 LAST SCH_NUMBER H4694802
J 0
(-1300 150);
DISPLAY 1.212766 (-1300 150);
PAINT YELLOW (-1300 150);
FORCEPROP 1 LAST SCH_ADDRESS3 Santa Clara, CA 95052-8119
J 0
(-3975 25);
DISPLAY 0.617021 (-3975 25);
PAINT GREEN (-3975 25);
FORCEPROP 1 LAST SCH_ADDRESS1 2200 Mission College Blvd.
J 0
(-3975 125);
DISPLAY 0.617021 (-3975 125);
PAINT GREEN (-3975 125);
FORCEPROP 1 LAST SCH_ADDRESS2 P.O. BOX 58119
J 0
(-3975 75);
DISPLAY 0.617021 (-3975 75);
PAINT GREEN (-3975 75);
FORCEPROP 1 LAST SCH_REV 2.420
J 0
(-250 150);
DISPLAY 0.978723 (-250 150);
PAINT YELLOW (-250 150);
FORCEPROP 1 LAST SCH_TITLE VCCIN CPU0 (2 OF 4)
J 0
(-7950 50);
DISPLAY 1.212766 (-7950 50);
PAINT ORANGE (-7950 50);
FORCEPROP 1 LAST SCH_DEPT BESD
J 1
(-4450 100);
DISPLAY 1.212766 (-4450 100);
PAINT YELLOW (-4450 100);
FORCEPROP 1 LAST COMMENT_BODY TRUE
J 0
(12 12);
DISPLAY 0.468085 (12 12);
PAINT GREEN (12 12);
DISPLAY INVISIBLE (12 12);
FORCEPROP 2 LAST CDS_LIB mstr_symbols
J 0
(0 0);
PAINT MONO (0 0);
DISPLAY INVISIBLE (0 0);
FORCEPROP 2 LAST PAGE_BORDER TRUE
J 0
(-7890 5250);
DISPLAY 0.638298 (-7890 5250);
PAINT PINK (-7890 5250);
DISPLAY INVISIBLE (-7890 5250);
FORCEPROP 2 LAST CDS_XR_PAGE_TITLE CR-202 : @BASEBOARD_FAB2_LIB.BASEBOARD_FAB2(SCH_1):PAGE202
J 0
(-7890 5250);
DISPLAY 0.638298 (-7890 5250);
PAINT PINK (-7890 5250);
DISPLAY INVISIBLE (-7890 5250);
WIRE 16 -1 (-2925 3400)(-2800 3400);
WIRE 16 -1 (-2800 3350)(-2800 3400);
WIRE 16 -1 (-2800 3300)(-2800 3350);
WIRE 16 -1 (-2800 3350)(-2925 3350);
WIRE 16 -1 (-2800 3250)(-2800 3300);
WIRE 16 -1 (-2800 3300)(-2925 3300);
WIRE 16 -1 (-2800 3175)(-2800 3250);
WIRE 16 -1 (-2800 3250)(-2925 3250);
WIRE 16 -1 (-3975 1325)(-4125 1325);
WIRE 16 -1 (-4125 1325)(-4125 325);
WIRE 16 -1 (-4125 325)(-1475 325);
WIRE 16 -1 (-1475 325)(-1475 925);
WIRE 16 -1 (-1600 925)(-1475 925);
WIRE 16 -1 (-1475 925)(-875 925);
WIRE 16 -1 (-875 750)(-875 925);
WIRE 16 -1 (-875 925)(-575 925);
WIRE 16 -1 (-575 750)(-575 925);
WIRE 16 -1 (-575 925)(-575 950);
WIRE 16 -1 (-875 450)(-875 550);
WIRE 16 -1 (-875 450)(-575 450);
WIRE 16 -1 (-575 550)(-575 450);
WIRE 16 -1 (-575 400)(-575 450);
WIRE 16 -1 (-2975 775)(-2800 775);
WIRE 16 -1 (-2800 725)(-2800 775);
WIRE 16 -1 (-2800 675)(-2800 725);
WIRE 16 -1 (-2800 725)(-2975 725);
WIRE 16 -1 (-2800 625)(-2800 675);
WIRE 16 -1 (-2800 675)(-2975 675);
WIRE 16 -1 (-2800 575)(-2800 625);
WIRE 16 -1 (-2800 625)(-2975 625);
WIRE 16 -1 (-3925 3950)(-4050 3950);
WIRE 16 -1 (-4050 3950)(-4050 2625);
WIRE 16 -1 (-4050 2625)(-1400 2625);
WIRE 16 -1 (-1400 2625)(-1400 3500);
WIRE 16 -1 (-1675 3500)(-1400 3500);
WIRE 16 -1 (-1400 3500)(-1250 3500);
WIRE 16 -1 (-1250 3400)(-1250 3500);
WIRE 16 -1 (-1075 3500)(-1250 3500);
WIRE 16 -1 (-875 3500)(-1075 3500);
WIRE 16 -1 (-1075 3500)(-1075 3625);
WIRE 16 -1 (-875 3400)(-875 3500);
WIRE 16 -1 (-4075 4250)(-3925 4250);
WIRE 16 -1 (-4075 4300)(-4075 4250);
WIRE 16 -1 (-3925 4300)(-4075 4300);
WIRE 16 -1 (-4075 4300)(-6050 4300);
WIRE 16 -1 (-6050 4125)(-6050 4300);
WIRE 16 -1 (-6050 4300)(-6325 4300);
WIRE 16 -1 (-6325 4150)(-6325 4300);
WIRE 16 -1 (-6325 4300)(-6600 4300);
WIRE 16 -1 (-6600 4150)(-6600 4300);
WIRE 16 -1 (-6600 4300)(-6900 4300);
WIRE 16 -1 (-6900 4175)(-6900 4300);
WIRE 16 -1 (-6900 4300)(-7200 4300);
WIRE 16 -1 (-7200 4175)(-7200 4300);
WIRE 16 -1 (-7200 4475)(-7200 4300);
WIRE 16 -1 (-5025 4025)(-5025 3800);
WIRE 16 -1 (-5025 3800)(-5125 3800);
WIRE 16 -1 (-5125 4025)(-5125 3800);
WIRE 16 -1 (-5125 3800)(-5750 3800);
WIRE 16 -1 (-5750 3925)(-5750 3800);
WIRE 16 -1 (-6050 3800)(-5750 3800);
WIRE 16 -1 (-6050 3925)(-6050 3800);
WIRE 16 -1 (-6050 3800)(-6325 3800);
WIRE 16 -1 (-6325 3950)(-6325 3800);
WIRE 16 -1 (-6325 3800)(-6600 3800);
WIRE 16 -1 (-6600 3950)(-6600 3800);
WIRE 16 -1 (-6600 3800)(-6900 3800);
WIRE 16 -1 (-6900 3975)(-6900 3800);
WIRE 16 -1 (-6900 3800)(-7200 3800);
WIRE 16 -1 (-7200 3975)(-7200 3800);
WIRE 16 -1 (-7200 3575)(-7200 3800);
WIRE 16 -1 (-3975 1625)(-4100 1625);
WIRE 16 -1 (-4100 1675)(-4100 1625);
WIRE 16 -1 (-3975 1675)(-4100 1675);
WIRE 16 -1 (-4100 1675)(-6225 1675);
WIRE 16 -1 (-6225 1575)(-6225 1675);
WIRE 16 -1 (-6225 1675)(-6450 1675);
WIRE 16 -1 (-6450 1525)(-6450 1675);
WIRE 16 -1 (-6450 1675)(-6725 1675);
WIRE 16 -1 (-6725 1525)(-6725 1675);
WIRE 16 -1 (-6725 1675)(-6975 1675);
WIRE 16 -1 (-6975 1550)(-6975 1675);
WIRE 16 -1 (-6975 1675)(-7225 1675);
WIRE 16 -1 (-7225 1575)(-7225 1675);
WIRE 16 -1 (-7225 1850)(-7225 1675);
WIRE 16 -1 (-5100 1325)(-5100 1175);
WIRE 16 -1 (-5100 1175)(-5225 1175);
WIRE 16 -1 (-5225 1350)(-5225 1175);
WIRE 16 -1 (-5225 1175)(-5950 1175);
WIRE 16 -1 (-5950 1325)(-5950 1175);
WIRE 16 -1 (-5950 1175)(-6225 1175);
WIRE 16 -1 (-6225 1375)(-6225 1175);
WIRE 16 -1 (-6225 1175)(-6450 1175);
WIRE 16 -1 (-6450 1325)(-6450 1175);
WIRE 16 -1 (-6450 1175)(-6725 1175);
WIRE 16 -1 (-6725 1325)(-6725 1175);
WIRE 16 -1 (-6725 1175)(-6975 1175);
WIRE 16 -1 (-6975 1350)(-6975 1175);
WIRE 16 -1 (-6975 1175)(-7225 1175);
WIRE 16 -1 (-7225 1375)(-7225 1175);
WIRE 16 -1 (-7225 1100)(-7225 1175);
WIRE 16 -1 (-3975 1425)(-4100 1425);
WIRE 16 -1 (-4100 1425)(-4100 1525);
WIRE 16 -1 (-3975 1525)(-4100 1525);
WIRE 16 -1 (-4100 1525)(-4700 1525);
WIRE 16 -1 (-4700 1525)(-4700 1975);
WIRE 16 -1 (-5100 1975)(-4700 1975);
WIRE 16 -1 (-4700 1975)(-4700 2050);
WIRE 16 -1 (-5225 1975)(-5100 1975);
WIRE 16 -1 (-5100 1525)(-5100 1975);
WIRE 16 -1 (-5225 1550)(-5225 1975);
WIRE 16 -1 (-5225 1975)(-5525 1975);
WIRE 16 -1 (-4050 4150)(-4050 4050);
WIRE 16 -1 (-4050 4150)(-3925 4150);
WIRE 16 -1 (-4675 4150)(-4050 4150);
WIRE 16 -1 (-4050 4050)(-3925 4050);
WIRE 16 -1 (-4675 4625)(-4675 4150);
WIRE 16 -1 (-4675 4625)(-5025 4625);
WIRE 16 -1 (-4675 4625)(-4675 4700);
WIRE 16 -1 (-5025 4625)(-5125 4625);
WIRE 16 -1 (-5025 4225)(-5025 4625);
WIRE 16 -1 (-5400 4625)(-5125 4625);
WIRE 16 -1 (-5125 4225)(-5125 4625);
WIRE 16 -1 (-750 3800)(-750 3750);
WIRE 16 -1 (-825 1250)(-825 1200);
WIRE 16 -1 (-4125 3200)(-4125 3100);
WIRE 16 -1 (-2350 3775)(-2350 3675);
WIRE 16 -1 (-2550 2925)(-2550 2850);
WIRE 16 -1 (-875 3200)(-875 3075);
WIRE 16 -1 (-875 3075)(-1000 3075);
WIRE 16 -1 (-1250 3075)(-1000 3075);
WIRE 16 -1 (-1000 3050)(-1000 3075);
WIRE 16 -1 (-1250 3075)(-1250 3200);
WIRE 16 -1 (-4175 575)(-4175 475);
WIRE 16 -1 (-2450 425)(-2450 450);
WIRE 16 -1 (-2450 1150)(-2450 1100);
WIRE 16 -1 (-5850 3350)(-4200 3350);
FORCEPROP 0 LAST VOLTAGE 5
J 0
(-5800 3425);
DISPLAY 1.021277 (-5800 3425);
PAINT SKYBLUE (-5800 3425);
DISPLAY INVISIBLE (-5800 3425);
FORCEPROP 2 LAST SIG_NAME VR_PVCCIN_CPU0_PH1_PHASE
J 0
(-5815 3360);
DISPLAY 0.617021 (-5815 3360);
PAINT ORANGE (-5815 3360);
FORCEPROP 2 LASTPROP $XRERR UNIQUE?
J 0
(-6055 3360);
DISPLAY 0.638298 (-6055 3360);
PAINT MONO (-6055 3360);
DISPLAY INVISIBLE (-6055 3360);
WIRE 16 -1 (-4200 3350)(-4200 3450);
WIRE 16 -1 (-4200 3450)(-3925 3450);
WIRE 3 2175 (-5175 3400)(-4775 3400);
WIRE 3 2175 (-5175 3675)(-5175 3400);
WIRE 3 2175 (-4775 3675)(-4775 3400);
WIRE 3 2175 (-5175 3675)(-4775 3675);
WIRE 16 2175 (-6125 3225)(-5425 3225);
WIRE 16 2175 (-6125 3675)(-6125 3225);
WIRE 16 2175 (-5425 3675)(-5425 3225);
WIRE 16 2175 (-6125 3675)(-5425 3675);
WIRE 16 -1 (-5025 3575)(-5850 3575);
FORCEPROP 2 LAST SIG_NAME VR_PVCCIN_CPU0_PH1_BOOT
J 0
(-5840 3585);
DISPLAY 0.617021 (-5840 3585);
PAINT ORANGE (-5840 3585);
FORCEPROP 2 LASTPROP $XRERR UNIQUE?
J 0
(-6080 3585);
DISPLAY 0.638298 (-6080 3585);
PAINT MONO (-6080 3585);
DISPLAY INVISIBLE (-6080 3585);
WIRE 16 -1 (-5850 3575)(-5850 3550);
WIRE 3 2175 (-2750 975)(-2075 975);
WIRE 3 2175 (-2750 975)(-2750 350);
WIRE 3 2175 (-2075 975)(-2075 350);
WIRE 3 2175 (-2750 350)(-2075 350);
WIRE 3 2175 (-2700 3475)(-2200 3475);
WIRE 3 2175 (-2700 3475)(-2700 2725);
WIRE 3 2175 (-2200 3475)(-2200 2725);
WIRE 3 2175 (-2700 2725)(-2200 2725);
WIRE 16 -1 (-4175 2100)(-1775 2100);
FORCEPROP 2 LAST SIG_NAME VR_PVCCIN_CPU0_AIREF2
J 0
(-2743 2132);
DISPLAY 0.617021 (-2743 2132);
PAINT ORANGE (-2743 2132);
WIRE 16 -1 (-4175 975)(-4175 2100);
WIRE 16 -1 (-4175 975)(-3975 975);
WIRE 16 -1 (-4175 775)(-4175 975);
WIRE 16 -1 (-2925 4150)(-750 4150);
FORCEPROP 2 LAST SIG_NAME VR_PVCCIN_CPU0_PH1_OCSET
J 0
(-2793 4166);
DISPLAY 0.617021 (-2793 4166);
PAINT ORANGE (-2793 4166);
FORCEPROP 2 LASTPROP $XRERR UNIQUE?
J 0
(-3033 4166);
DISPLAY 0.638298 (-3033 4166);
PAINT MONO (-3033 4166);
DISPLAY INVISIBLE (-3033 4166);
WIRE 16 -1 (-750 4000)(-750 4150);
WIRE 16 -1 (-2925 4000)(-2350 4000);
FORCEPROP 2 LAST SIG_NAME A_TSENSE_PVCCIN_CPU0
J 0
(-2887 4010);
DISPLAY 0.617021 (-2887 4010);
PAINT ORANGE (-2887 4010);
WIRE 16 -1 (-2925 4000)(-2925 3850);
WIRE 16 -1 (-1750 4000)(-2350 4000);
WIRE 16 -1 (-2350 3975)(-2350 4000);
WIRE 3 2175 (-2450 4050)(-2125 4050);
WIRE 3 2175 (-2450 4050)(-2450 3550);
WIRE 3 2175 (-2125 4050)(-2125 3550);
WIRE 3 2175 (-2450 3550)(-2125 3550);
WIRE 3 2175 (-5175 1050)(-4850 1050);
WIRE 3 2175 (-5175 1050)(-5175 775);
WIRE 3 2175 (-4850 1050)(-4850 775);
WIRE 3 2175 (-5175 775)(-4850 775);
WIRE 16 -1 (-5950 725)(-4250 725);
FORCEPROP 0 LAST VOLTAGE 5
J 0
(-5925 800);
DISPLAY 1.021277 (-5925 800);
PAINT SKYBLUE (-5925 800);
DISPLAY INVISIBLE (-5925 800);
FORCEPROP 2 LAST SIG_NAME VR_PVCCIN_CPU0_PH2_PHASE
J 0
(-5928 731);
DISPLAY 0.617021 (-5928 731);
PAINT ORANGE (-5928 731);
FORCEPROP 2 LASTPROP $XRERR UNIQUE?
J 0
(-6168 731);
DISPLAY 0.638298 (-6168 731);
PAINT MONO (-6168 731);
DISPLAY INVISIBLE (-6168 731);
WIRE 16 -1 (-4250 725)(-4250 825);
WIRE 16 -1 (-4250 825)(-3975 825);
WIRE 3 2175 (-4425 925)(-3900 925);
WIRE 3 2175 (-4425 925)(-4425 350);
WIRE 3 2175 (-3900 925)(-3900 350);
WIRE 3 2175 (-4425 350)(-3900 350);
WIRE 16 -1 (-3975 875)(-4250 875);
WIRE 16 -1 (-4250 875)(-4250 950);
WIRE 16 -1 (-4250 950)(-4875 950);
FORCEPROP 2 LAST SIG_NAME VR_PVCCIN_CPU0_PH2_BOOT_R
J 0
(-4842 960);
DISPLAY 0.617021 (-4842 960);
PAINT ORANGE (-4842 960);
FORCEPROP 2 LASTPROP $XRERR UNIQUE?
J 0
(-5082 960);
DISPLAY 0.638298 (-5082 960);
PAINT MONO (-5082 960);
DISPLAY INVISIBLE (-5082 960);
WIRE 16 2175 (-5475 1600)(-4875 1600);
WIRE 16 2175 (-5475 1600)(-5475 1200);
WIRE 16 2175 (-4875 1600)(-4875 1200);
WIRE 16 2175 (-5475 1200)(-4875 1200);
WIRE 16 -1 (-6675 1075)(-3975 1075);
FORCEPROP 2 LAST SIG_NAME VR_PVCCIN_CPU0_PWM2
J 0
(-6688 1085);
DISPLAY 0.617021 (-6688 1085);
PAINT ORANGE (-6688 1085);
WIRE 16 -1 (-2975 1525)(-825 1525);
FORCEPROP 0 LAST VOLTAGE 3.6
J 0
(-2900 1600);
DISPLAY 1.021277 (-2900 1600);
PAINT SKYBLUE (-2900 1600);
DISPLAY INVISIBLE (-2900 1600);
FORCEPROP 2 LAST SIG_NAME VR_PVCCIN_CPU0_PH2_OCSET
J 0
(-2843 1541);
DISPLAY 0.617021 (-2843 1541);
PAINT ORANGE (-2843 1541);
FORCEPROP 2 LASTPROP $XRERR UNIQUE?
J 0
(-3083 1541);
DISPLAY 0.638298 (-3083 1541);
PAINT MONO (-3083 1541);
DISPLAY INVISIBLE (-3083 1541);
WIRE 16 -1 (-825 1525)(-825 1450);
WIRE 3 2175 (-2525 1425)(-2050 1425);
WIRE 3 2175 (-2525 1425)(-2525 1000);
WIRE 3 2175 (-2050 1425)(-2050 1000);
WIRE 3 2175 (-2525 1000)(-2050 1000);
WIRE 3 2175 (-4375 3000)(-3950 3000);
WIRE 3 2175 (-4375 3550)(-4375 3000);
WIRE 3 2175 (-3950 3550)(-3950 3000);
WIRE 3 2175 (-4375 3550)(-3950 3550);
WIRE 16 -1 (-5950 1725)(-3975 1725);
FORCEPROP 0 LAST VOLTAGE 5
J 0
(-4575 1800);
DISPLAY 1.021277 (-4575 1800);
PAINT SKYBLUE (-4575 1800);
DISPLAY INVISIBLE (-4575 1800);
FORCEPROP 2 LAST SIG_NAME VR_PVCCIN_CPU0_PH2_VCIN
J 0
(-5840 1735);
DISPLAY 0.617021 (-5840 1735);
PAINT ORANGE (-5840 1735);
FORCEPROP 2 LASTPROP $XRERR UNIQUE?
J 0
(-6080 1735);
DISPLAY 0.638298 (-6080 1735);
PAINT MONO (-6080 1735);
DISPLAY INVISIBLE (-6080 1735);
WIRE 16 -1 (-5950 1975)(-5950 1725);
WIRE 16 -1 (-5950 1525)(-5950 1725);
WIRE 16 -1 (-5950 1975)(-5725 1975);
WIRE 16 -1 (-3925 3700)(-6650 3700);
WIRE 16 2175 (-6275 575)(-5200 575);
WIRE 16 2175 (-6275 1025)(-6275 575);
WIRE 16 2175 (-5200 1025)(-5200 575);
WIRE 16 2175 (-6275 1025)(-5200 1025);
WIRE 16 -1 (-2975 1725)(-1725 1725);
FORCEPROP 2 LAST SIG_NAME ISENSE_PVCCIN_CPU0_PH2_IMON
J 0
(-2814 1731);
DISPLAY 0.617021 (-2814 1731);
PAINT ORANGE (-2814 1731);
WIRE 16 -1 (-2975 1375)(-2450 1375);
FORCEPROP 2 LAST SIG_NAME A_TSENSE_PVCCIN_CPU0
J 0
(-2964 1387);
DISPLAY 0.617021 (-2964 1387);
PAINT ORANGE (-2964 1387);
WIRE 16 -1 (-2975 1375)(-2975 1225);
WIRE 16 -1 (-1725 1375)(-2450 1375);
WIRE 16 -1 (-2450 1350)(-2450 1375);
WIRE 16 -1 (-1800 925)(-2450 925);
WIRE 16 -1 (-2450 875)(-2450 925);
WIRE 16 -1 (-2450 925)(-2975 925);
FORCEPROP 0 LAST VOLTAGE 5
J 0
(-2825 1000);
DISPLAY 1.021277 (-2825 1000);
PAINT SKYBLUE (-2825 1000);
DISPLAY INVISIBLE (-2825 1000);
FORCEPROP 2 LAST SIG_NAME VR_PVCCIN_CPU0_PHASE2
J 0
(-2715 935);
DISPLAY 0.617021 (-2715 935);
PAINT ORANGE (-2715 935);
FORCEPROP 2 LASTPROP $XRERR UNIQUE?
J 0
(-2955 935);
DISPLAY 0.638298 (-2955 935);
PAINT MONO (-2955 935);
DISPLAY INVISIBLE (-2955 935);
WIRE 16 -1 (-2975 925)(-2975 875);
WIRE 16 -1 (-2975 1475)(-2300 1475);
FORCEPROP 2 LAST SIG_NAME NC_PVCCIN_CPU0_PH2_P31
J 0
(-2888 1485);
DISPLAY 0.617021 (-2888 1485);
PAINT ORANGE (-2888 1485);
FORCEPROP 2 LASTPROP $XRERR UNIQUE?
J 0
(-2270 1475);
DISPLAY 0.638298 (-2270 1475);
PAINT MONO (-2270 1475);
DISPLAY INVISIBLE (-2270 1475);
WIRE 16 -1 (-3975 1175)(-4725 1175);
FORCEPROP 0 LAST SIG_NAME TP_PVCCIN_CPU0_PH2_GL_0
J 0
(-4698 1190);
DISPLAY 0.617021 (-4698 1190);
PAINT ORANGE (-4698 1190);
FORCEPROP 2 LASTPROP $XRERR UNIQUE?
J 0
(-4965 1175);
DISPLAY 0.638298 (-4965 1175);
PAINT MONO (-4965 1175);
DISPLAY INVISIBLE (-4965 1175);
WIRE 16 -1 (-3975 1225)(-4725 1225);
FORCEPROP 0 LAST SIG_NAME TP_PVCCIN_CPU0_PH2_GL_1
J 0
(-4698 1240);
DISPLAY 0.617021 (-4698 1240);
PAINT ORANGE (-4698 1240);
FORCEPROP 2 LASTPROP $XRERR UNIQUE?
J 0
(-4965 1225);
DISPLAY 0.638298 (-4965 1225);
PAINT MONO (-4965 1225);
DISPLAY INVISIBLE (-4965 1225);
WIRE 16 -1 (-5075 950)(-5950 950);
FORCEPROP 2 LAST SIG_NAME VR_PVCCIN_CPU0_PH2_BOOT
J 0
(-5967 960);
DISPLAY 0.617021 (-5967 960);
PAINT ORANGE (-5967 960);
FORCEPROP 2 LASTPROP $XRERR UNIQUE?
J 0
(-6207 960);
DISPLAY 0.638298 (-6207 960);
PAINT MONO (-6207 960);
DISPLAY INVISIBLE (-6207 960);
WIRE 16 -1 (-5950 950)(-5950 925);
WIRE 16 -1 (-2925 4100)(-2175 4100);
FORCEPROP 2 LAST SIG_NAME NC_PVCCIN_CPU0_PH1_P31
J 0
(-2778 4101);
DISPLAY 0.617021 (-2778 4101);
PAINT ORANGE (-2778 4101);
FORCEPROP 2 LASTPROP $XRERR UNIQUE?
J 0
(-2145 4100);
DISPLAY 0.638298 (-2145 4100);
PAINT MONO (-2145 4100);
DISPLAY INVISIBLE (-2145 4100);
WIRE 16 -1 (-2925 3500)(-2550 3500);
FORCEPROP 2 LAST SIG_NAME VR_PVCCIN_CPU0_PHASE1
J 0
(-2815 3510);
DISPLAY 0.617021 (-2815 3510);
PAINT ORANGE (-2815 3510);
FORCEPROP 2 LASTPROP $XRERR UNIQUE?
J 0
(-3055 3510);
DISPLAY 0.638298 (-3055 3510);
PAINT MONO (-3055 3510);
DISPLAY INVISIBLE (-3055 3510);
WIRE 16 -1 (-2550 3500)(-1875 3500);
FORCEPROP 0 LAST VOLTAGE 5
J 0
(-2500 3575);
DISPLAY 1.021277 (-2500 3575);
PAINT SKYBLUE (-2500 3575);
DISPLAY INVISIBLE (-2500 3575);
WIRE 16 -1 (-2550 3425)(-2550 3500);
WIRE 16 -1 (-2550 3275)(-2550 3175);
WIRE 16 -1 (-3925 3800)(-4650 3800);
FORCEPROP 0 LAST SIG_NAME TP_PVCCIN_CPU0_PH1_GL_0
J 0
(-4623 3815);
DISPLAY 0.617021 (-4623 3815);
PAINT ORANGE (-4623 3815);
FORCEPROP 2 LASTPROP $XRERR UNIQUE?
J 0
(-4890 3800);
DISPLAY 0.638298 (-4890 3800);
PAINT MONO (-4890 3800);
DISPLAY INVISIBLE (-4890 3800);
WIRE 16 -1 (-3925 3850)(-4650 3850);
FORCEPROP 0 LAST SIG_NAME TP_PVCCIN_CPU0_PH1_GL_1
J 0
(-4623 3865);
DISPLAY 0.617021 (-4623 3865);
PAINT ORANGE (-4623 3865);
FORCEPROP 2 LASTPROP $XRERR UNIQUE?
J 0
(-4890 3850);
DISPLAY 0.638298 (-4890 3850);
PAINT MONO (-4890 3850);
DISPLAY INVISIBLE (-4890 3850);
WIRE 16 -1 (-4825 3575)(-4200 3575);
FORCEPROP 2 LAST SIG_NAME VR_PVCCIN_CPU0_PH1_BOOT_R
J 0
(-4760 3578);
DISPLAY 0.617021 (-4760 3578);
PAINT ORANGE (-4760 3578);
FORCEPROP 2 LASTPROP $XRERR UNIQUE?
J 0
(-5000 3578);
DISPLAY 0.638298 (-5000 3578);
PAINT MONO (-5000 3578);
DISPLAY INVISIBLE (-5000 3578);
WIRE 16 -1 (-4200 3575)(-4200 3500);
WIRE 16 -1 (-4200 3500)(-3925 3500);
WIRE 16 -1 (-5750 4350)(-3925 4350);
FORCEPROP 0 LAST VOLTAGE 5
J 0
(-4525 4425);
DISPLAY 1.021277 (-4525 4425);
PAINT SKYBLUE (-4525 4425);
DISPLAY INVISIBLE (-4525 4425);
FORCEPROP 2 LAST SIG_NAME VR_PVCCIN_CPU0_PH1_VCIN
J 0
(-5690 4360);
DISPLAY 0.617021 (-5690 4360);
PAINT ORANGE (-5690 4360);
FORCEPROP 2 LASTPROP $XRERR UNIQUE?
J 0
(-5930 4360);
DISPLAY 0.638298 (-5930 4360);
PAINT MONO (-5930 4360);
DISPLAY INVISIBLE (-5930 4360);
WIRE 16 -1 (-5750 4350)(-5750 4625);
WIRE 16 -1 (-5750 4125)(-5750 4350);
WIRE 16 -1 (-5750 4625)(-5600 4625);
WIRE 16 -1 (-3925 3600)(-4125 3600);
WIRE 16 -1 (-4125 3600)(-4125 4750);
WIRE 16 -1 (-4125 3400)(-4125 3600);
WIRE 16 -1 (-4125 4750)(-1450 4750);
FORCEPROP 2 LAST SIG_NAME VR_PVCCIN_CPU0_AIREF1
J 0
(-2907 4761);
DISPLAY 0.617021 (-2907 4761);
PAINT ORANGE (-2907 4761);
WIRE 16 -1 (-2925 4350)(-1600 4350);
FORCEPROP 2 LAST SIG_NAME ISENSE_PVCCIN_CPU0_PH1_IMON
J 0
(-2635 4360);
DISPLAY 0.617021 (-2635 4360);
PAINT ORANGE (-2635 4360);
WIRE 16 2175 (-5400 4275)(-4725 4275);
WIRE 16 2175 (-5400 4275)(-5400 3825);
WIRE 16 2175 (-4725 4275)(-4725 3825);
WIRE 16 2175 (-5400 3825)(-4725 3825);
WIRE 16 -1 (-2450 725)(-2450 700);
DOT 1 (-4100 1675);
DOT 1 (-2450 1375);
DOT 1 (-2800 725);
DOT 1 (-4175 975);
DOT 1 (-5950 1725);
DOT 1 (-4100 1525);
DOT 1 (-5125 3800);
DOT 1 (-4125 3600);
DOT 1 (-7225 1175);
DOT 1 (-7225 1675);
DOT 1 (-6975 1175);
DOT 1 (-6725 1175);
DOT 1 (-6975 1675);
DOT 1 (-6725 1675);
DOT 1 (-6450 1175);
DOT 1 (-6225 1175);
DOT 1 (-6225 1675);
DOT 1 (-7200 3800);
DOT 1 (-6900 3800);
DOT 1 (-6325 3800);
DOT 1 (-5225 1175);
DOT 1 (-5225 1975);
DOT 1 (-5100 1975);
DOT 1 (-4700 1975);
DOT 1 (-6050 3800);
DOT 1 (-5125 4625);
DOT 1 (-5025 4625);
DOT 1 (-4675 4625);
DOT 1 (-2800 3250);
DOT 1 (-1400 3500);
DOT 1 (-1250 3500);
DOT 1 (-1075 3500);
DOT 1 (-1000 3075);
DOT 1 (-2450 925);
DOT 1 (-6450 1675);
DOT 1 (-2800 625);
DOT 1 (-2800 675);
DOT 1 (-7200 4300);
DOT 1 (-6900 4300);
DOT 1 (-6050 4300);
DOT 1 (-6600 4300);
DOT 1 (-6325 4300);
DOT 1 (-6600 3800);
DOT 1 (-5750 4350);
DOT 1 (-4075 4300);
DOT 1 (-4050 4150);
DOT 1 (-2550 3500);
DOT 1 (-2800 3350);
DOT 1 (-2800 3300);
DOT 1 (-5950 1175);
DOT 1 (-575 450);
DOT 1 (-575 925);
DOT 1 (-875 925);
DOT 1 (-1475 925);
DOT 1 (-2350 4000);
DOT 1 (-5750 3800);
FORCENOTE
ROOM=PVCCIN_CPU0_PWR_VR
(-7880 185) 0;
DISPLAY LEFT (-7880 185);
DISPLAY 2.446809 (-7880 185);
PAINT PURPLE (-7880 185);
FORCENOTE
SPOF
(-6005 575) 0;
DISPLAY LEFT (-6005 575);
DISPLAY 1.808511 (-6005 575);
PAINT PURPLE (-6005 575);
FORCENOTE
PLACE ON TOP
(-5405 3725) 0;
DISPLAY LEFT (-5405 3725);
DISPLAY 1.553191 (-5405 3725);
PAINT PURPLE (-5405 3725);
FORCENOTE
SPOF
(-6030 3125) 0;
DISPLAY LEFT (-6030 3125);
DISPLAY 1.936170 (-6030 3125);
PAINT PURPLE (-6030 3125);
FORCENOTE
PLACE ON TOP
(-5505 1100) 0;
DISPLAY LEFT (-5505 1100);
DISPLAY 1.553191 (-5505 1100);
PAINT PURPLE (-5505 1100);
FORCENOTE
TP FAB1 CO-LAY WITH TI PARTS 11/16
(-5300 500) 0;
DISPLAY LEFT (-5300 500);
DISPLAY 0.851064 (-5300 500);
PAINT RED (-5300 500);
FORCENOTE
TP FAB1 CO-LAY WITH TI PARTS 11/16
(-2025 450) 0;
DISPLAY LEFT (-2025 450);
DISPLAY 0.851064 (-2025 450);
PAINT RED (-2025 450);
FORCENOTE
TP FAB1 CO-LAY WITH TI PARTS 11/16
(-2050 1200) 0;
DISPLAY LEFT (-2050 1200);
DISPLAY 1.021277 (-2050 1200);
PAINT RED (-2050 1200);
FORCENOTE
TP FAB1 3.01 OHM NEED CHANGE TO 2.2 OHM BUT WAIT FOR SYMBOL
(-2000 375) 0;
DISPLAY LEFT (-2000 375);
DISPLAY 0.851064 (-2000 375);
PAINT RED (-2000 375);
FORCENOTE
TP FAB1 CO-LAY WITH TI PARTS 11/16
(-2100 3775) 0;
DISPLAY LEFT (-2100 3775);
DISPLAY 1.021277 (-2100 3775);
PAINT RED (-2100 3775);
FORCENOTE
TP FAB1 3.01 OHM NEED CHANGE TO 2.2 OHM BUT WAIT FOR SYMBOL
(-3375 2475) 0;
DISPLAY LEFT (-3375 2475);
DISPLAY 1.021277 (-3375 2475);
PAINT RED (-3375 2475);
FORCENOTE
TP FAB1 CO-LAY WITH TI PARTS 11/16
(-3400 2550) 0;
DISPLAY LEFT (-3400 2550);
DISPLAY 1.021277 (-3400 2550);
PAINT RED (-3400 2550);
FORCENOTE
TP FAB1 CO-LAY WITH TI PARTS 11/16
(-5375 3025) 0;
DISPLAY LEFT (-5375 3025);
DISPLAY 0.851064 (-5375 3025);
PAINT RED (-5375 3025);
QUIT
